G04 ================== begin FILE IDENTIFICATION RECORD ==================*
G04 Layout Name:  16368-sb.brd*
G04 Film Name:    DRILL*
G04 File Format:  Gerber RS274X*
G04 File Origin:  Cadence Allegro 16.5-S056*
G04 Origin Date:  Tue Feb 07 09:07:40 2017*
G04 *
G04 Layer:  MANUFACTURING/NCLEGEND-1-6*
G04 Layer:  MANUFACTURING/DRILL SIZE*
G04 Layer:  DRAWING FORMAT/LAYER_PCB_STORY*
G04 Layer:  DRAWING FORMAT/LAYER_DRILL*
G04 Layer:  BOARD GEOMETRY/PANEL_OUTLINE*
G04 *
G04 Offset:    (0.00 0.00)*
G04 Mirror:    No*
G04 Mode:      Positive*
G04 Rotation:  0*
G04 FullContactRelief:  No*
G04 UndefLineWidth:     6.00*
G04 ================== end FILE IDENTIFICATION RECORD ====================*
%FSLAX35Y35*MOIN*%
%IR0*IPPOS*OFA0.00000B0.00000*MIA0B0*SFA1.00000B1.00000*%
%AMMACRO15*
1,1,.006,.005,0.0*
20,1,.006,.005,0.0,-.005,0.0,0.0*
1,1,.006,-.005,0.0*
1,1,.006,0.0,.005*
20,1,.006,0.0,.005,0.0,-.005,0.0*
1,1,.006,0.0,-.005*
1,1,.006,.0025,0.0*
20,1,.006,.0025,0.0,.0025,.005,0.0*
1,1,.006,.0025,.005*
20,1,.006,.0025,.005,.0015,.004,0.0*
1,1,.006,.0015,.004*
1,1,.006,.0015,0.0*
20,1,.006,.0015,0.0,.0035,0.0,0.0*
1,1,.006,.0035,0.0*
%
%ADD15MACRO15*%
%AMMACRO11*
1,1,.006,.01,.01*
20,1,.006,.01,.01,.01,-.01,0.0*
1,1,.006,.01,-.01*
20,1,.006,.01,-.01,-.01,-.01,0.0*
1,1,.006,-.01,-.01*
20,1,.006,-.01,-.01,-.01,.01,0.0*
1,1,.006,-.01,.01*
20,1,.006,-.01,.01,.01,.01,0.0*
1,1,.006,.01,.01*
1,1,.006,-.00317,.00333*
20,1,.006,-.00317,.00333,-.00217,.00433,0.0*
1,1,.006,-.00217,.00433*
20,1,.006,-.00217,.00433,-.001,.00483,0.0*
1,1,.006,-.001,.00483*
20,1,.006,-.001,.00483,.00033,.005,0.0*
1,1,.006,.00033,.005*
20,1,.006,.00033,.005,.002,.00467,0.0*
1,1,.006,.002,.00467*
20,1,.006,.002,.00467,.00317,.00383,0.0*
1,1,.006,.00317,.00383*
20,1,.006,.00317,.00383,.0035,.00283,0.0*
1,1,.006,.0035,.00283*
20,1,.006,.0035,.00283,.00333,.00183,0.0*
1,1,.006,.00333,.00183*
20,1,.006,.00333,.00183,.00267,.001,0.0*
1,1,.006,.00267,.001*
20,1,.006,.00267,.001,-.00067,-.00067,0.0*
1,1,.006,-.00067,-.00067*
20,1,.006,-.00067,-.00067,-.00217,-.00183,0.0*
1,1,.006,-.00217,-.00183*
20,1,.006,-.00217,-.00183,-.00317,-.0035,0.0*
1,1,.006,-.00317,-.0035*
20,1,.006,-.00317,-.0035,-.0035,-.005,0.0*
1,1,.006,-.0035,-.005*
20,1,.006,-.0035,-.005,.0035,-.005,0.0*
1,1,.006,.0035,-.005*
%
%ADD11MACRO11*%
%AMMACRO16*
1,1,.006,.008284,-.02*
20,1,.006,.008284,-.02,-.008284,-.02,0.0*
1,1,.006,-.008284,-.02*
20,1,.006,-.008284,-.02,-.02,-.008284,0.0*
1,1,.006,-.02,-.008284*
20,1,.006,-.02,-.008284,-.02,.008284,0.0*
1,1,.006,-.02,.008284*
20,1,.006,-.02,.008284,-.008284,.02,0.0*
1,1,.006,-.008284,.02*
20,1,.006,-.008284,.02,.008284,.02,0.0*
1,1,.006,.008284,.02*
20,1,.006,.008284,.02,.02,.008284,0.0*
1,1,.006,.02,.008284*
20,1,.006,.02,.008284,.02,-.008284,0.0*
1,1,.006,.02,-.008284*
20,1,.006,.02,-.008284,.008284,-.02,0.0*
1,1,.006,.008284,-.02*
1,1,.006,-.00733,-.007*
20,1,.006,-.00733,-.007,-.00533,-.00867,0.0*
1,1,.006,-.00533,-.00867*
20,1,.006,-.00533,-.00867,-.003,-.00967,0.0*
1,1,.006,-.003,-.00967*
20,1,.006,-.003,-.00967,0.0,-.01,0.0*
1,1,.006,0.0,-.01*
20,1,.006,0.0,-.01,.003,-.00933,0.0*
1,1,.006,.003,-.00933*
20,1,.006,.003,-.00933,.00533,-.008,0.0*
1,1,.006,.00533,-.008*
20,1,.006,.00533,-.008,.007,-.00567,0.0*
1,1,.006,.007,-.00567*
20,1,.006,.007,-.00567,.00733,-.003,0.0*
1,1,.006,.00733,-.003*
20,1,.006,.00733,-.003,.00667,-.00033,0.0*
1,1,.006,.00667,-.00033*
20,1,.006,.00667,-.00033,.005,.00133,0.0*
1,1,.006,.005,.00133*
20,1,.006,.005,.00133,.00267,.00267,0.0*
1,1,.006,.00267,.00267*
20,1,.006,.00267,.00267,.00033,.003,0.0*
1,1,.006,.00033,.003*
20,1,.006,.00033,.003,-.002,.00267,0.0*
1,1,.006,-.002,.00267*
20,1,.006,-.002,.00267,-.005,.00133,0.0*
1,1,.006,-.005,.00133*
20,1,.006,-.005,.00133,-.004,.01,0.0*
1,1,.006,-.004,.01*
20,1,.006,-.004,.01,.005,.01,0.0*
1,1,.006,.005,.01*
%
%ADD16MACRO16*%
%AMMACRO12*
1,1,.006,.043,0.0*
20,1,.006,.043,0.0,0.0,-.043,0.0*
1,1,.006,0.0,-.043*
20,1,.006,0.0,-.043,-.043,0.0,0.0*
1,1,.006,-.043,0.0*
20,1,.006,-.043,0.0,0.0,.043,0.0*
1,1,.006,0.0,.043*
20,1,.006,0.0,.043,.043,0.0,0.0*
1,1,.006,.043,0.0*
1,1,.006,-.01362,-.00358*
20,1,.006,-.01362,-.00358,-.0086,.00143,0.0*
1,1,.006,-.0086,.00143*
20,1,.006,-.0086,.00143,-.0043,.0043,0.0*
1,1,.006,-.0043,.0043*
20,1,.006,-.0043,.0043,.00143,.00573,0.0*
1,1,.006,.00143,.00573*
20,1,.006,.00143,.00573,.00645,.0043,0.0*
1,1,.006,.00645,.0043*
20,1,.006,.00645,.0043,.01003,.00143,0.0*
1,1,.006,.01003,.00143*
20,1,.006,.01003,.00143,.0129,-.00287,0.0*
1,1,.006,.0129,-.00287*
20,1,.006,.0129,-.00287,.01362,-.00788,0.0*
1,1,.006,.01362,-.00788*
20,1,.006,.01362,-.00788,.0129,-.01218,0.0*
1,1,.006,.0129,-.01218*
20,1,.006,.0129,-.01218,.01003,-.01648,0.0*
1,1,.006,.01003,-.01648*
20,1,.006,.01003,-.01648,.00573,-.02007,0.0*
1,1,.006,.00573,-.02007*
20,1,.006,.00573,-.02007,.00072,-.0215,0.0*
1,1,.006,.00072,-.0215*
20,1,.006,.00072,-.0215,-.00502,-.02007,0.0*
1,1,.006,-.00502,-.02007*
20,1,.006,-.00502,-.02007,-.01003,-.01577,0.0*
1,1,.006,-.01003,-.01577*
20,1,.006,-.01003,-.01577,-.0129,-.00932,0.0*
1,1,.006,-.0129,-.00932*
20,1,.006,-.0129,-.00932,-.01362,-.00215,0.0*
1,1,.006,-.01362,-.00215*
20,1,.006,-.01362,-.00215,-.01218,.00717,0.0*
1,1,.006,-.01218,.00717*
20,1,.006,-.01218,.00717,-.01003,.01218,0.0*
1,1,.006,-.01003,.01218*
20,1,.006,-.01003,.01218,-.00645,.0172,0.0*
1,1,.006,-.00645,.0172*
20,1,.006,-.00645,.0172,-.00143,.02078,0.0*
1,1,.006,-.00143,.02078*
20,1,.006,-.00143,.02078,.00358,.0215,0.0*
1,1,.006,.00358,.0215*
20,1,.006,.00358,.0215,.0086,.02007,0.0*
1,1,.006,.0086,.02007*
20,1,.006,.0086,.02007,.01218,.01648,0.0*
1,1,.006,.01218,.01648*
%
%ADD12MACRO12*%
%AMMACRO17*
1,1,.006,-.0085,.0115*
20,1,.006,-.0085,.0115,.0085,.0115,0.0*
1,1,.006,.0085,.0115*
20,1,.006,.0085,.0115,.010497,.011325,0.0*
1,1,.006,.010497,.011325*
20,1,.006,.010497,.011325,.012433,.010806,0.0*
1,1,.006,.012433,.010806*
20,1,.006,.012433,.010806,.01425,.009959,0.0*
1,1,.006,.01425,.009959*
20,1,.006,.01425,.009959,.015892,.00881,0.0*
1,1,.006,.015892,.00881*
20,1,.006,.015892,.00881,.01731,.007392,0.0*
1,1,.006,.01731,.007392*
20,1,.006,.01731,.007392,.018459,.00575,0.0*
1,1,.006,.018459,.00575*
20,1,.006,.018459,.00575,.019306,.003933,0.0*
1,1,.006,.019306,.003933*
20,1,.006,.019306,.003933,.019825,.001997,0.0*
1,1,.006,.019825,.001997*
20,1,.006,.019825,.001997,.02,0.0,0.0*
1,1,.006,.02,0.0*
20,1,.006,.02,0.0,.019825,-.001997,0.0*
1,1,.006,.019825,-.001997*
20,1,.006,.019825,-.001997,.019306,-.003933,0.0*
1,1,.006,.019306,-.003933*
20,1,.006,.019306,-.003933,.018459,-.00575,0.0*
1,1,.006,.018459,-.00575*
20,1,.006,.018459,-.00575,.01731,-.007392,0.0*
1,1,.006,.01731,-.007392*
20,1,.006,.01731,-.007392,.015892,-.00881,0.0*
1,1,.006,.015892,-.00881*
20,1,.006,.015892,-.00881,.01425,-.009959,0.0*
1,1,.006,.01425,-.009959*
20,1,.006,.01425,-.009959,.012433,-.010806,0.0*
1,1,.006,.012433,-.010806*
20,1,.006,.012433,-.010806,.010497,-.011325,0.0*
1,1,.006,.010497,-.011325*
20,1,.006,.010497,-.011325,.0085,-.0115,0.0*
1,1,.006,.0085,-.0115*
20,1,.006,.0085,-.0115,-.0085,-.0115,0.0*
1,1,.006,-.0085,-.0115*
20,1,.006,-.0085,-.0115,-.010497,-.011325,0.0*
1,1,.006,-.010497,-.011325*
20,1,.006,-.010497,-.011325,-.012433,-.010806,0.0*
1,1,.006,-.012433,-.010806*
20,1,.006,-.012433,-.010806,-.01425,-.009959,0.0*
1,1,.006,-.01425,-.009959*
20,1,.006,-.01425,-.009959,-.015892,-.00881,0.0*
1,1,.006,-.015892,-.00881*
20,1,.006,-.015892,-.00881,-.01731,-.007392,0.0*
1,1,.006,-.01731,-.007392*
20,1,.006,-.01731,-.007392,-.018459,-.00575,0.0*
1,1,.006,-.018459,-.00575*
20,1,.006,-.018459,-.00575,-.019306,-.003933,0.0*
1,1,.006,-.019306,-.003933*
20,1,.006,-.019306,-.003933,-.019825,-.001997,0.0*
1,1,.006,-.019825,-.001997*
20,1,.006,-.019825,-.001997,-.02,0.0,0.0*
1,1,.006,-.02,0.0*
20,1,.006,-.02,0.0,-.019825,.001997,0.0*
1,1,.006,-.019825,.001997*
20,1,.006,-.019825,.001997,-.019306,.003933,0.0*
1,1,.006,-.019306,.003933*
20,1,.006,-.019306,.003933,-.018459,.00575,0.0*
1,1,.006,-.018459,.00575*
20,1,.006,-.018459,.00575,-.01731,.007392,0.0*
1,1,.006,-.01731,.007392*
20,1,.006,-.01731,.007392,-.015892,.00881,0.0*
1,1,.006,-.015892,.00881*
20,1,.006,-.015892,.00881,-.01425,.009959,0.0*
1,1,.006,-.01425,.009959*
20,1,.006,-.01425,.009959,-.012433,.010806,0.0*
1,1,.006,-.012433,.010806*
20,1,.006,-.012433,.010806,-.010497,.011325,0.0*
1,1,.006,-.010497,.011325*
20,1,.006,-.010497,.011325,-.0085,.0115,0.0*
1,1,.006,-.0085,.0115*
1,1,.006,0.0,-.00575*
20,1,.006,0.0,-.00575,.00134,-.00556,0.0*
1,1,.006,.00134,-.00556*
20,1,.006,.00134,-.00556,.00287,-.00498,0.0*
1,1,.006,.00287,-.00498*
20,1,.006,.00287,-.00498,.00383,-.00403,0.0*
1,1,.006,.00383,-.00403*
20,1,.006,.00383,-.00403,.00422,-.00268,0.0*
1,1,.006,.00422,-.00268*
20,1,.006,.00422,-.00268,.00383,-.00134,0.0*
1,1,.006,.00383,-.00134*
20,1,.006,.00383,-.00134,.00268,-.00019,0.0*
1,1,.006,.00268,-.00019*
20,1,.006,.00268,-.00019,.00096,.00038,0.0*
1,1,.006,.00096,.00038*
20,1,.006,.00096,.00038,-.00096,.00038,0.0*
1,1,.006,-.00096,.00038*
20,1,.006,-.00096,.00038,-.00211,.00077,0.0*
1,1,.006,-.00211,.00077*
20,1,.006,-.00211,.00077,-.00307,.00172,0.0*
1,1,.006,-.00307,.00172*
20,1,.006,-.00307,.00172,-.00345,.00307,0.0*
1,1,.006,-.00345,.00307*
20,1,.006,-.00345,.00307,-.00287,.00441,0.0*
1,1,.006,-.00287,.00441*
20,1,.006,-.00287,.00441,-.00153,.00537,0.0*
1,1,.006,-.00153,.00537*
20,1,.006,-.00153,.00537,0.0,.00575,0.0*
1,1,.006,0.0,.00575*
20,1,.006,0.0,.00575,.00153,.00537,0.0*
1,1,.006,.00153,.00537*
20,1,.006,.00153,.00537,.00287,.00441,0.0*
1,1,.006,.00287,.00441*
20,1,.006,.00287,.00441,.00345,.00307,0.0*
1,1,.006,.00345,.00307*
20,1,.006,.00345,.00307,.00307,.00172,0.0*
1,1,.006,.00307,.00172*
20,1,.006,.00307,.00172,.00211,.00077,0.0*
1,1,.006,.00211,.00077*
20,1,.006,.00211,.00077,.00096,.00038,0.0*
1,1,.006,.00096,.00038*
20,1,.006,.00096,.00038,-.00096,.00038,0.0*
1,1,.006,-.00096,.00038*
20,1,.006,-.00096,.00038,-.00268,-.00019,0.0*
1,1,.006,-.00268,-.00019*
20,1,.006,-.00268,-.00019,-.00383,-.00134,0.0*
1,1,.006,-.00383,-.00134*
20,1,.006,-.00383,-.00134,-.00422,-.00268,0.0*
1,1,.006,-.00422,-.00268*
20,1,.006,-.00422,-.00268,-.00383,-.00403,0.0*
1,1,.006,-.00383,-.00403*
20,1,.006,-.00383,-.00403,-.00287,-.00498,0.0*
1,1,.006,-.00287,-.00498*
20,1,.006,-.00287,-.00498,-.00134,-.00556,0.0*
1,1,.006,-.00134,-.00556*
20,1,.006,-.00134,-.00556,0.0,-.00575,0.0*
1,1,.006,0.0,-.00575*
%
%ADD17MACRO17*%
%AMMACRO13*
1,1,.006,0.0,.013*
20,1,.006,0.0,.013,-.011258,.0065,0.0*
1,1,.006,-.011258,.0065*
20,1,.006,-.011258,.0065,-.011258,-.0065,0.0*
1,1,.006,-.011258,-.0065*
20,1,.006,-.011258,-.0065,0.0,-.013,0.0*
1,1,.006,0.0,-.013*
20,1,.006,0.0,-.013,.011258,-.0065,0.0*
1,1,.006,.011258,-.0065*
20,1,.006,.011258,-.0065,.011258,.0065,0.0*
1,1,.006,.011258,.0065*
20,1,.006,.011258,.0065,0.0,.013,0.0*
1,1,.006,0.0,.013*
1,1,.006,.0026,-.0065*
20,1,.006,.0026,-.0065,.0026,.0065,0.0*
1,1,.006,.0026,.0065*
20,1,.006,.0026,.0065,-.00542,-.00282,0.0*
1,1,.006,-.00542,-.00282*
20,1,.006,-.00542,-.00282,.00542,-.00282,0.0*
1,1,.006,.00542,-.00282*
%
%ADD13MACRO13*%
%AMMACRO14*
1,1,.006,.014,0.0*
20,1,.006,.014,0.0,.007,.012124,0.0*
1,1,.006,.007,.012124*
20,1,.006,.007,.012124,-.007,.012124,0.0*
1,1,.006,-.007,.012124*
20,1,.006,-.007,.012124,-.014,0.0,0.0*
1,1,.006,-.014,0.0*
20,1,.006,-.014,0.0,-.007,-.012124,0.0*
1,1,.006,-.007,-.012124*
20,1,.006,-.007,-.012124,.007,-.012124,0.0*
1,1,.006,.007,-.012124*
20,1,.006,.007,-.012124,.014,0.0,0.0*
1,1,.006,.014,0.0*
1,1,.006,-.00513,-.0042*
20,1,.006,-.00513,-.0042,-.00373,-.00583,0.0*
1,1,.006,-.00373,-.00583*
20,1,.006,-.00373,-.00583,-.00187,-.00677,0.0*
1,1,.006,-.00187,-.00677*
20,1,.006,-.00187,-.00677,.00023,-.007,0.0*
1,1,.006,.00023,-.007*
20,1,.006,.00023,-.007,.0021,-.00677,0.0*
1,1,.006,.0021,-.00677*
20,1,.006,.0021,-.00677,.00397,-.0056,0.0*
1,1,.006,.00397,-.0056*
20,1,.006,.00397,-.0056,.00513,-.0042,0.0*
1,1,.006,.00513,-.0042*
20,1,.006,.00513,-.0042,.00537,-.0028,0.0*
1,1,.006,.00537,-.0028*
20,1,.006,.00537,-.0028,.0049,-.00117,0.0*
1,1,.006,.0049,-.00117*
20,1,.006,.0049,-.00117,.00327,0.0,0.0*
1,1,.006,.00327,0.0*
20,1,.006,.00327,0.0,.00163,.00047,0.0*
1,1,.006,.00163,.00047*
20,1,.006,.00163,.00047,-.00047,.00047,0.0*
1,1,.006,-.00047,.00047*
1,1,.006,.00163,.00047*
20,1,.006,.00163,.00047,.00303,.00117,0.0*
1,1,.006,.00303,.00117*
20,1,.006,.00303,.00117,.0042,.00233,0.0*
1,1,.006,.0042,.00233*
20,1,.006,.0042,.00233,.00467,.00373,0.0*
1,1,.006,.00467,.00373*
20,1,.006,.00467,.00373,.0042,.00513,0.0*
1,1,.006,.0042,.00513*
20,1,.006,.0042,.00513,.00303,.0063,0.0*
1,1,.006,.00303,.0063*
20,1,.006,.00303,.0063,.00093,.007,0.0*
1,1,.006,.00093,.007*
20,1,.006,.00093,.007,-.00117,.00677,0.0*
1,1,.006,-.00117,.00677*
20,1,.006,-.00117,.00677,-.00327,.00583,0.0*
1,1,.006,-.00327,.00583*
%
%ADD14MACRO14*%
%AMMACRO10*
1,1,.006,0.0,.0825*
20,1,.006,0.0,.0825,.0825,-.0825,0.0*
1,1,.006,.0825,-.0825*
20,1,.006,.0825,-.0825,-.0825,-.0825,0.0*
1,1,.006,-.0825,-.0825*
20,1,.006,-.0825,-.0825,0.0,.0825,0.0*
1,1,.006,0.0,.0825*
1,1,.006,-.00275,-.04125*
20,1,.006,-.00275,-.04125,0.0,-.02338,0.0*
1,1,.006,0.0,-.02338*
20,1,.006,0.0,-.02338,.00413,-.00825,0.0*
1,1,.006,.00413,-.00825*
20,1,.006,.00413,-.00825,.00962,.0055,0.0*
1,1,.006,.00962,.0055*
20,1,.006,.00962,.0055,.0165,.02062,0.0*
1,1,.006,.0165,.02062*
20,1,.006,.0165,.02062,.0275,.04125,0.0*
1,1,.006,.0275,.04125*
20,1,.006,.0275,.04125,-.0275,.04125,0.0*
1,1,.006,-.0275,.04125*
%
%ADD10MACRO10*%
%ADD18C,.02*%
%ADD19C,.006*%
G75*
%LPD*%
G75*
G54D10*
X17717Y19685D03*
X159449D03*
X643950Y115650D03*
G54D11*
X28802Y13285D03*
X24117Y8600D03*
X11317D03*
X6632Y13285D03*
Y26085D03*
X11317Y30770D03*
X24117D03*
X28802Y26085D03*
X170534Y13285D03*
X165849Y8600D03*
X153049D03*
X148364Y13285D03*
Y26085D03*
X153049Y30770D03*
X165849D03*
X170534Y26085D03*
X643950Y256150D03*
G54D12*
X9000Y48000D03*
X164500Y48500D03*
X643950Y143750D03*
G54D13*
X26890Y46949D03*
X643950Y199950D03*
G54D14*
X32205Y38484D03*
Y55414D03*
X51103Y38484D03*
Y55414D03*
X643950Y228050D03*
G54D15*
X28100Y39300D03*
X34200Y47000D03*
X28100Y55300D03*
X20000Y55000D03*
X15000Y45000D03*
X5000Y38000D03*
Y55000D03*
X30827Y47067D03*
X68750Y24100D03*
X79940Y26850D03*
X70700Y11200D03*
X40100Y21692D03*
X35000Y5000D03*
X41200Y7400D03*
X98200Y16500D03*
X108140Y28132D03*
X109000Y11000D03*
X95400Y12500D03*
X84100Y14900D03*
X81500Y12700D03*
X74200Y21700D03*
X53437Y13900D03*
X71405Y19607D03*
X68500Y13800D03*
X98000Y25500D03*
X69000Y17200D03*
X84700Y26702D03*
X65300Y24437D03*
X65800Y21000D03*
X46000Y25600D03*
X54500Y25500D03*
X98700Y21000D03*
X95300D03*
X85100Y21100D03*
X56200Y21000D03*
X52800D03*
X45250Y35850D03*
X36733Y47067D03*
X111800Y52264D03*
X96000Y55600D03*
X44607Y46831D03*
X39400D03*
X111700Y39600D03*
X52218Y47067D03*
X56000Y55500D03*
X103700Y36400D03*
X39300Y35500D03*
X47200Y47067D03*
X49730Y46821D03*
X87900Y53100D03*
X103655Y52264D03*
X61300Y47250D03*
X88940Y39400D03*
X76000Y37750D03*
X87700Y43400D03*
X94800Y46800D03*
X93000Y49700D03*
X58000Y38500D03*
X74000Y34900D03*
X119400Y29800D03*
X143000Y5000D03*
X137000Y12750D03*
X133500Y15700D03*
X118300Y19900D03*
X134200Y9000D03*
X131000Y6000D03*
X127500Y52264D03*
X119500Y33900D03*
X127500Y37000D03*
X170000Y45000D03*
X135500D03*
X155000D03*
X165000Y55000D03*
X145000D03*
Y36500D03*
X119403Y52264D03*
X643950Y284250D03*
G54D16*
X103642Y43898D03*
X127264D03*
X643950Y171850D03*
G54D17*
X56418Y46949D03*
X643950Y87550D03*
G54D18*
G01X-149983Y-76117D02*
Y-156117D01*
G01D02*
X864117D01*
G01X-153983Y-60117D02*
G02I-12000J0D01*
G01X-159133D02*
G02I-6850J0D01*
G01X-165983Y-76117D02*
Y-44117D01*
G01X-149983Y-60117D02*
X-181983D01*
G01X-149983Y-76117D02*
X864117D01*
G01X-149983Y-111617D02*
X864117D01*
G01X76617Y-76117D02*
Y-156117D01*
G01X214117Y-76117D02*
Y-156117D01*
G01X329117Y-76117D02*
Y-156117D01*
G01X496617Y-76117D02*
Y-156117D01*
G01X666617Y-76117D02*
Y-156117D01*
G01X864117Y-76117D02*
Y-156117D01*
G01X892117Y-60117D02*
G02I-12000J0D01*
G01X886967D02*
G02I-6850J0D01*
G01X880117Y-76117D02*
Y-44117D01*
G01X896117Y-60117D02*
X864117D01*
G54D19*
G01X-137600Y-128617D02*
Y-146117D01*
X-128866D01*
G01X-113987Y-136784D02*
X-113113Y-135909D01*
X-112458Y-134451D01*
X-112021Y-132408D01*
X-112458Y-130659D01*
X-113331Y-129492D01*
X-114860Y-128617D01*
X-120755D01*
Y-146117D01*
X-113550D01*
X-112021Y-144951D01*
X-111148Y-143200D01*
X-110711Y-141159D01*
X-111148Y-139117D01*
X-112458Y-137367D01*
X-113987Y-136784D01*
X-120755D01*
G01X-93430Y-130076D02*
X-94740Y-129200D01*
X-96268Y-128617D01*
X-98015D01*
X-99980Y-129492D01*
X-101508Y-130950D01*
X-102600Y-132701D01*
X-103473Y-135617D01*
X-103692Y-138242D01*
X-103255Y-140867D01*
X-102600Y-142617D01*
X-101290Y-144367D01*
X-99761Y-145534D01*
X-98233Y-146117D01*
X-96705D01*
X-95176Y-145534D01*
X-93866Y-144659D01*
X-92774Y-143493D01*
G01X-67600Y-128617D02*
Y-146117D01*
X-58866D01*
G01X-41366D02*
X-50100D01*
Y-128617D01*
X-41366D01*
G01X-44860Y-137075D02*
X-50100D01*
G01X-33036Y-146117D02*
Y-128617D01*
X-28670D01*
X-26923Y-129492D01*
X-25613Y-130659D01*
X-24521Y-132408D01*
X-23648Y-134451D01*
X-23430Y-137367D01*
X-23648Y-140284D01*
X-24521Y-142326D01*
X-25613Y-144076D01*
X-26923Y-145242D01*
X-28670Y-146117D01*
X-33036D01*
G01X10260Y-135909D02*
X8732Y-134742D01*
X7422Y-134451D01*
X5675Y-135034D01*
X4365Y-136200D01*
X3492Y-138242D01*
X3273Y-140284D01*
X3492Y-142326D01*
X4365Y-144076D01*
X5675Y-145534D01*
X7422Y-146117D01*
X8950Y-145534D01*
X10260Y-144367D01*
G01X28197Y-146117D02*
Y-134451D01*
G01Y-136492D02*
X27324Y-135326D01*
X26013Y-134742D01*
X24485Y-134451D01*
X22957Y-135034D01*
X21647Y-136200D01*
X20773Y-137950D01*
X20337Y-140284D01*
X20773Y-142617D01*
X21647Y-144367D01*
X22957Y-145534D01*
X24485Y-146117D01*
X26013Y-145825D01*
X27324Y-144951D01*
X28197Y-143784D01*
G01X38710Y-146117D02*
Y-134451D01*
G01Y-136784D02*
X39802Y-135617D01*
X40894Y-134742D01*
X42422Y-134451D01*
X43513Y-134742D01*
X44824Y-135617D01*
G01X63197Y-128617D02*
Y-146117D01*
G01Y-143493D02*
X62324Y-144951D01*
X61013Y-145825D01*
X59485Y-146117D01*
X57739Y-145534D01*
X56429Y-144076D01*
X55555Y-142326D01*
X55337Y-140284D01*
X55555Y-138242D01*
X56429Y-136492D01*
X57739Y-135034D01*
X59485Y-134451D01*
X61013Y-134742D01*
X62105Y-135326D01*
X63197Y-136492D01*
G01X-77660Y-101117D02*
Y-83617D01*
X-71983Y-98200D01*
X-66306Y-83617D01*
Y-101117D01*
G01X-54483D02*
X-55793Y-100825D01*
X-57103Y-99659D01*
X-57977Y-97617D01*
X-58413Y-95284D01*
X-57977Y-92950D01*
X-57103Y-90909D01*
X-55793Y-89742D01*
X-54483Y-89451D01*
X-53173Y-89742D01*
X-51863Y-90909D01*
X-50990Y-92950D01*
X-50771Y-95284D01*
X-50990Y-97617D01*
X-51863Y-99659D01*
X-53173Y-100825D01*
X-54483Y-101117D01*
G01X-33053Y-83617D02*
Y-101117D01*
G01Y-98493D02*
X-33926Y-99951D01*
X-35237Y-100825D01*
X-36765Y-101117D01*
X-38511Y-100534D01*
X-39821Y-99076D01*
X-40695Y-97326D01*
X-40913Y-95284D01*
X-40695Y-93242D01*
X-39821Y-91492D01*
X-38511Y-90034D01*
X-36765Y-89451D01*
X-35237Y-89742D01*
X-34145Y-90326D01*
X-33053Y-91492D01*
G01X-22758Y-93242D02*
X-15771D01*
X-16426Y-91200D01*
X-17518Y-90034D01*
X-19046Y-89451D01*
X-20575Y-89742D01*
X-21885Y-90617D01*
X-22758Y-92659D01*
X-23195Y-94409D01*
Y-96159D01*
X-22758Y-97909D01*
X-21666Y-99659D01*
X-20356Y-100825D01*
X-18828Y-101117D01*
X-17300Y-100534D01*
X-15771Y-98784D01*
G01X-1983Y-101117D02*
Y-83617D01*
G01X110317Y-146117D02*
Y-128617D01*
X107697Y-132117D01*
G01Y-146117D02*
X112937D01*
G01X123669Y-138826D02*
X125197Y-136784D01*
X126507Y-135617D01*
X128254Y-135034D01*
X129782Y-135617D01*
X130874Y-136784D01*
X131747Y-138534D01*
X131965Y-140575D01*
X131747Y-142326D01*
X130874Y-144076D01*
X129563Y-145534D01*
X128035Y-146117D01*
X126289Y-145534D01*
X124760Y-143784D01*
X123887Y-141159D01*
X123669Y-138242D01*
X124105Y-134451D01*
X124760Y-132408D01*
X125852Y-130367D01*
X127380Y-128909D01*
X128909Y-128617D01*
X130437Y-129200D01*
X131529Y-130659D01*
G01X140514Y-142617D02*
X141823Y-144659D01*
X143570Y-145825D01*
X145535Y-146117D01*
X147282Y-145825D01*
X149029Y-144367D01*
X150120Y-142617D01*
X150339Y-140867D01*
X149902Y-138826D01*
X148374Y-137367D01*
X146845Y-136784D01*
X144880D01*
G01X146845D02*
X148155Y-135909D01*
X149247Y-134451D01*
X149684Y-132701D01*
X149247Y-130950D01*
X148155Y-129492D01*
X146190Y-128617D01*
X144225Y-128909D01*
X142260Y-130076D01*
G01X158669Y-138826D02*
X160197Y-136784D01*
X161507Y-135617D01*
X163254Y-135034D01*
X164782Y-135617D01*
X165874Y-136784D01*
X166747Y-138534D01*
X166965Y-140575D01*
X166747Y-142326D01*
X165874Y-144076D01*
X164563Y-145534D01*
X163035Y-146117D01*
X161289Y-145534D01*
X159760Y-143784D01*
X158887Y-141159D01*
X158669Y-138242D01*
X159105Y-134451D01*
X159760Y-132408D01*
X160852Y-130367D01*
X162380Y-128909D01*
X163909Y-128617D01*
X165437Y-129200D01*
X166529Y-130659D01*
G01X180317Y-146117D02*
X181845Y-145825D01*
X183592Y-144951D01*
X184684Y-143493D01*
X185120Y-141450D01*
X184684Y-139409D01*
X183374Y-137659D01*
X181409Y-136784D01*
X179225D01*
X177915Y-136200D01*
X176823Y-134742D01*
X176387Y-132701D01*
X177042Y-130659D01*
X178570Y-129200D01*
X180317Y-128617D01*
X182063Y-129200D01*
X183592Y-130659D01*
X184247Y-132701D01*
X183810Y-134742D01*
X182719Y-136200D01*
X181409Y-136784D01*
X179225D01*
X177260Y-137659D01*
X175950Y-139409D01*
X175514Y-141450D01*
X175950Y-143493D01*
X177042Y-144951D01*
X178789Y-145825D01*
X180317Y-146117D01*
G01X97200Y-101117D02*
Y-83617D01*
X102440D01*
X104187Y-84492D01*
X105497Y-86534D01*
X105934Y-88867D01*
X105497Y-91200D01*
X104405Y-92950D01*
X102440Y-93826D01*
X97200D01*
G01X123870Y-85076D02*
X122560Y-84200D01*
X121032Y-83617D01*
X119285D01*
X117320Y-84492D01*
X115792Y-85950D01*
X114700Y-87701D01*
X113827Y-90617D01*
X113608Y-93242D01*
X114045Y-95867D01*
X114700Y-97617D01*
X116010Y-99367D01*
X117539Y-100534D01*
X119067Y-101117D01*
X120595D01*
X122124Y-100534D01*
X123434Y-99659D01*
X124526Y-98493D01*
G01X138313Y-91784D02*
X139187Y-90909D01*
X139842Y-89451D01*
X140279Y-87408D01*
X139842Y-85659D01*
X138969Y-84492D01*
X137440Y-83617D01*
X131545D01*
Y-101117D01*
X138750D01*
X140279Y-99951D01*
X141152Y-98200D01*
X141589Y-96159D01*
X141152Y-94117D01*
X139842Y-92367D01*
X138313Y-91784D01*
X131545D01*
G01X147517Y-106950D02*
X160617D01*
G01X166545Y-101117D02*
Y-83617D01*
X176589Y-101117D01*
Y-83617D01*
G01X189067Y-101117D02*
X187320Y-100825D01*
X185792Y-99659D01*
X184482Y-97909D01*
X183608Y-95867D01*
X183172Y-93534D01*
Y-91200D01*
X183608Y-88867D01*
X184482Y-86825D01*
X185792Y-85076D01*
X187320Y-83909D01*
X189067Y-83617D01*
X190813Y-83909D01*
X192342Y-85076D01*
X193652Y-86825D01*
X194526Y-88867D01*
X194962Y-91200D01*
Y-93534D01*
X194526Y-95867D01*
X193652Y-97909D01*
X192342Y-99659D01*
X190813Y-100825D01*
X189067Y-101117D01*
G01X58424Y46953D02*
X64558Y47765D01*
G01X63184Y49096D02*
X58424Y46953D01*
X63578Y46122D01*
X63184Y49096D01*
G01X55568Y45799D02*
X57268D01*
G03Y48099I0J1150D01*
G01X55568D01*
G03Y45799I0J-1150D01*
G01X258282Y-143784D02*
X260029Y-145242D01*
X261994Y-146117D01*
X263740D01*
X265487Y-145242D01*
X266797Y-143784D01*
X267452Y-141742D01*
X267015Y-139701D01*
X265924Y-137950D01*
X263959Y-136784D01*
X261339Y-136200D01*
X259810Y-135034D01*
X259155Y-132992D01*
X259592Y-130950D01*
X260684Y-129492D01*
X262212Y-128617D01*
X263740D01*
X265269Y-129200D01*
X266579Y-130659D01*
G01X282113Y-136784D02*
X282987Y-135909D01*
X283642Y-134451D01*
X284079Y-132408D01*
X283642Y-130659D01*
X282769Y-129492D01*
X281240Y-128617D01*
X275345D01*
Y-146117D01*
X282550D01*
X284079Y-144951D01*
X284952Y-143200D01*
X285389Y-141159D01*
X284952Y-139117D01*
X283642Y-137367D01*
X282113Y-136784D01*
X275345D01*
G01X239908Y-83617D02*
X245367Y-101117D01*
X250826Y-83617D01*
G01X267234Y-101117D02*
X258500D01*
Y-83617D01*
X267234D01*
G01X263740Y-92075D02*
X258500D01*
G01X276000Y-101117D02*
Y-83617D01*
X281459D01*
X283205Y-84492D01*
X284297Y-85659D01*
X284734Y-87992D01*
X284297Y-90326D01*
X282987Y-91784D01*
X281459Y-92659D01*
X276000D01*
G01X281459D02*
X284734Y-101117D01*
G01X297867Y-101700D02*
X297430Y-101409D01*
Y-100825D01*
X297867Y-100534D01*
X298304Y-100825D01*
Y-101409D01*
X297867Y-101700D01*
G01X373014Y-146117D02*
Y-128617D01*
X377380D01*
X379127Y-129492D01*
X380437Y-130659D01*
X381529Y-132408D01*
X382402Y-134451D01*
X382620Y-137367D01*
X382402Y-140284D01*
X381529Y-142326D01*
X380437Y-144076D01*
X379127Y-145242D01*
X377380Y-146117D01*
X373014D01*
G01X390950D02*
Y-128617D01*
X396409D01*
X398155Y-129492D01*
X399247Y-130659D01*
X399684Y-132992D01*
X399247Y-135326D01*
X397937Y-136784D01*
X396409Y-137659D01*
X390950D01*
G01X396409D02*
X399684Y-146117D01*
G01X410197Y-128617D02*
X415437D01*
G01X412817D02*
Y-146117D01*
G01X410197D02*
X415437D01*
G01X425950Y-128617D02*
Y-146117D01*
X434684D01*
G01X443450Y-128617D02*
Y-146117D01*
X452184D01*
G01X373450Y-83617D02*
Y-101117D01*
X382184D01*
G01X399247D02*
Y-89451D01*
G01Y-91492D02*
X398374Y-90326D01*
X397063Y-89742D01*
X395535Y-89451D01*
X394007Y-90034D01*
X392697Y-91200D01*
X391823Y-92950D01*
X391387Y-95284D01*
X391823Y-97617D01*
X392697Y-99367D01*
X394007Y-100534D01*
X395535Y-101117D01*
X397063Y-100825D01*
X398374Y-99951D01*
X399247Y-98784D01*
G01X408232Y-106367D02*
X409542Y-106950D01*
X411289Y-106367D01*
X412380Y-105201D01*
X413254Y-103742D01*
X414563Y-99076D01*
X417402Y-89451D01*
G01X410415D02*
X414563Y-99076D01*
G01X427042Y-93242D02*
X434029D01*
X433374Y-91200D01*
X432282Y-90034D01*
X430754Y-89451D01*
X429225Y-89742D01*
X427915Y-90617D01*
X427042Y-92659D01*
X426605Y-94409D01*
Y-96159D01*
X427042Y-97909D01*
X428134Y-99659D01*
X429444Y-100825D01*
X430972Y-101117D01*
X432500Y-100534D01*
X434029Y-98784D01*
G01X444760Y-101117D02*
Y-89451D01*
G01Y-91784D02*
X445852Y-90617D01*
X446944Y-89742D01*
X448472Y-89451D01*
X449563Y-89742D01*
X450874Y-90617D01*
G01X515564Y-101117D02*
Y-83617D01*
X519930D01*
X521677Y-84492D01*
X522987Y-85659D01*
X524079Y-87408D01*
X524952Y-89451D01*
X525170Y-92367D01*
X524952Y-95284D01*
X524079Y-97326D01*
X522987Y-99076D01*
X521677Y-100242D01*
X519930Y-101117D01*
X515564D01*
G01X534592Y-93242D02*
X541579D01*
X540924Y-91200D01*
X539832Y-90034D01*
X538304Y-89451D01*
X536775Y-89742D01*
X535465Y-90617D01*
X534592Y-92659D01*
X534155Y-94409D01*
Y-96159D01*
X534592Y-97909D01*
X535684Y-99659D01*
X536994Y-100825D01*
X538522Y-101117D01*
X540050Y-100534D01*
X541579Y-98784D01*
G01X552092Y-99076D02*
X553184Y-100242D01*
X554712Y-101117D01*
X556022D01*
X557332Y-100534D01*
X558205Y-99659D01*
X558642Y-98493D01*
X558424Y-96742D01*
X557550Y-95867D01*
X553620Y-94117D01*
X552747Y-92075D01*
X553184Y-90617D01*
X554057Y-89742D01*
X555367Y-89451D01*
X556677Y-89742D01*
X557987Y-90617D01*
G01X572867Y-89451D02*
Y-101117D01*
G01Y-84784D02*
X572430Y-84492D01*
Y-83909D01*
X572867Y-83617D01*
X573304Y-83909D01*
Y-84492D01*
X572867Y-84784D01*
G01X587310Y-105492D02*
X588839Y-106659D01*
X590585Y-106950D01*
X592113Y-106659D01*
X593424Y-105201D01*
X594297Y-103159D01*
Y-89451D01*
G01Y-91784D02*
X593424Y-90617D01*
X592113Y-89742D01*
X590585Y-89451D01*
X588839Y-90034D01*
X587747Y-91200D01*
X586873Y-93242D01*
X586437Y-95284D01*
X586655Y-97034D01*
X587529Y-99076D01*
X588839Y-100534D01*
X590585Y-101117D01*
X591895Y-100825D01*
X593424Y-99659D01*
X594297Y-98493D01*
G01X604155Y-101117D02*
Y-89451D01*
G01Y-92367D02*
X605029Y-90909D01*
X606339Y-89742D01*
X608085Y-89451D01*
X609613Y-89742D01*
X610924Y-90909D01*
X611579Y-92950D01*
Y-101117D01*
G01X622092Y-93242D02*
X629079D01*
X628424Y-91200D01*
X627332Y-90034D01*
X625804Y-89451D01*
X624275Y-89742D01*
X622965Y-90617D01*
X622092Y-92659D01*
X621655Y-94409D01*
Y-96159D01*
X622092Y-97909D01*
X623184Y-99659D01*
X624494Y-100825D01*
X626022Y-101117D01*
X627550Y-100534D01*
X629079Y-98784D01*
G01X639810Y-101117D02*
Y-89451D01*
G01Y-91784D02*
X640902Y-90617D01*
X641994Y-89742D01*
X643522Y-89451D01*
X644613Y-89742D01*
X645924Y-90617D01*
G01X559969Y-128617D02*
X568265D01*
X559969Y-146117D01*
X568265D01*
G01X581617D02*
X579870Y-145825D01*
X578342Y-144659D01*
X577032Y-142909D01*
X576158Y-140867D01*
X575722Y-138534D01*
Y-136200D01*
X576158Y-133867D01*
X577032Y-131825D01*
X578342Y-130076D01*
X579870Y-128909D01*
X581617Y-128617D01*
X583363Y-128909D01*
X584892Y-130076D01*
X586202Y-131825D01*
X587076Y-133867D01*
X587512Y-136200D01*
Y-138534D01*
X587076Y-140867D01*
X586202Y-142909D01*
X584892Y-144659D01*
X583363Y-145825D01*
X581617Y-146117D01*
G01X603484D02*
X594750D01*
Y-128617D01*
X603484D01*
G01X599990Y-137075D02*
X594750D01*
G01X600085Y43500D02*
Y56000D01*
X607215Y43500D01*
Y56000D01*
G01X616050Y43500D02*
X615120Y43708D01*
X614190Y44541D01*
X613570Y46000D01*
X613260Y47667D01*
X613570Y49333D01*
X614190Y50792D01*
X615120Y51625D01*
X616050Y51833D01*
X616980Y51625D01*
X617910Y50792D01*
X618530Y49333D01*
X618685Y47667D01*
X618530Y46000D01*
X617910Y44541D01*
X616980Y43708D01*
X616050Y43500D01*
G01X628450Y56000D02*
Y43500D01*
G01X626280Y51833D02*
X630620D01*
G01X638525Y49125D02*
X643485D01*
X643020Y50583D01*
X642245Y51417D01*
X641160Y51833D01*
X640075Y51625D01*
X639145Y51000D01*
X638525Y49542D01*
X638215Y48291D01*
Y47042D01*
X638525Y45792D01*
X639300Y44541D01*
X640230Y43708D01*
X641315Y43500D01*
X642400Y43917D01*
X643485Y45166D01*
G01X653250Y43083D02*
X652940Y43292D01*
Y43708D01*
X653250Y43917D01*
X653560Y43708D01*
Y43292D01*
X653250Y43083D01*
G01Y48708D02*
X652940Y48917D01*
Y49333D01*
X653250Y49542D01*
X653560Y49333D01*
Y48917D01*
X653250Y48708D01*
G01X662550Y43500D02*
Y56000D01*
X666425D01*
X667665Y55375D01*
X668440Y54542D01*
X668750Y52875D01*
X668440Y51208D01*
X667510Y50167D01*
X666425Y49542D01*
X662550D01*
G01X666425D02*
X668750Y43500D01*
G01X675725Y49125D02*
X680685D01*
X680220Y50583D01*
X679445Y51417D01*
X678360Y51833D01*
X677275Y51625D01*
X676345Y51000D01*
X675725Y49542D01*
X675415Y48291D01*
Y47042D01*
X675725Y45792D01*
X676500Y44541D01*
X677430Y43708D01*
X678515Y43500D01*
X679600Y43917D01*
X680685Y45166D01*
G01X689520Y43500D02*
Y54125D01*
X689830Y55166D01*
X690450Y55792D01*
X691380Y56000D01*
X692310Y55583D01*
X692775Y54542D01*
G01X690915Y51000D02*
X687815D01*
G01X700525Y49125D02*
X705485D01*
X705020Y50583D01*
X704245Y51417D01*
X703160Y51833D01*
X702075Y51625D01*
X701145Y51000D01*
X700525Y49542D01*
X700215Y48291D01*
Y47042D01*
X700525Y45792D01*
X701300Y44541D01*
X702230Y43708D01*
X703315Y43500D01*
X704400Y43917D01*
X705485Y45166D01*
G01X713080Y43500D02*
Y51833D01*
G01Y50167D02*
X713855Y51000D01*
X714630Y51625D01*
X715715Y51833D01*
X716490Y51625D01*
X717420Y51000D01*
G01X740050Y56000D02*
Y43500D01*
G01X737880Y51833D02*
X742220D01*
G01X752450Y43500D02*
X751520Y43708D01*
X750590Y44541D01*
X749970Y46000D01*
X749660Y47667D01*
X749970Y49333D01*
X750590Y50792D01*
X751520Y51625D01*
X752450Y51833D01*
X753380Y51625D01*
X754310Y50792D01*
X754930Y49333D01*
X755085Y47667D01*
X754930Y46000D01*
X754310Y44541D01*
X753380Y43708D01*
X752450Y43500D01*
G01X773840D02*
Y56000D01*
X776940D01*
X778180Y55375D01*
X779110Y54542D01*
X779885Y53292D01*
X780505Y51833D01*
X780660Y49750D01*
X780505Y47667D01*
X779885Y46208D01*
X779110Y44958D01*
X778180Y44125D01*
X776940Y43500D01*
X773840D01*
G01X786550D02*
Y56000D01*
X790425D01*
X791665Y55375D01*
X792440Y54542D01*
X792750Y52875D01*
X792440Y51208D01*
X791510Y50167D01*
X790425Y49542D01*
X786550D01*
G01X790425D02*
X792750Y43500D01*
G01X800190Y56000D02*
X803910D01*
G01X802050D02*
Y43500D01*
G01X800190D02*
X803910D01*
G01X811350Y56000D02*
Y43500D01*
X817550D01*
G01X823750Y56000D02*
Y43500D01*
X829950D01*
G01X851650D02*
Y56000D01*
G01X866840Y43500D02*
Y51833D01*
G01Y50375D02*
X866220Y51208D01*
X865290Y51625D01*
X864205Y51833D01*
X863120Y51417D01*
X862190Y50583D01*
X861570Y49333D01*
X861260Y47667D01*
X861570Y46000D01*
X862190Y44750D01*
X863120Y43917D01*
X864205Y43500D01*
X865290Y43708D01*
X866220Y44333D01*
X866840Y45166D01*
G01X873195Y39750D02*
X874125Y39333D01*
X875365Y39750D01*
X876140Y40583D01*
X876760Y41625D01*
X877690Y44958D01*
X879705Y51833D01*
G01X874745D02*
X877690Y44958D01*
G01X886525Y49125D02*
X891485D01*
X891020Y50583D01*
X890245Y51417D01*
X889160Y51833D01*
X888075Y51625D01*
X887145Y51000D01*
X886525Y49542D01*
X886215Y48291D01*
Y47042D01*
X886525Y45792D01*
X887300Y44541D01*
X888230Y43708D01*
X889315Y43500D01*
X890400Y43917D01*
X891485Y45166D01*
G01X899080Y43500D02*
Y51833D01*
G01Y50167D02*
X899855Y51000D01*
X900630Y51625D01*
X901715Y51833D01*
X902490Y51625D01*
X903420Y51000D01*
G01X925120Y43500D02*
Y54125D01*
X925430Y55166D01*
X926050Y55792D01*
X926980Y56000D01*
X927910Y55583D01*
X928375Y54542D01*
G01X926515Y51000D02*
X923415D01*
G01X938450Y43500D02*
X937520Y43708D01*
X936590Y44541D01*
X935970Y46000D01*
X935660Y47667D01*
X935970Y49333D01*
X936590Y50792D01*
X937520Y51625D01*
X938450Y51833D01*
X939380Y51625D01*
X940310Y50792D01*
X940930Y49333D01*
X941085Y47667D01*
X940930Y46000D01*
X940310Y44541D01*
X939380Y43708D01*
X938450Y43500D01*
G01X948680D02*
Y51833D01*
G01Y50167D02*
X949455Y51000D01*
X950230Y51625D01*
X951315Y51833D01*
X952090Y51625D01*
X953020Y51000D01*
G01X978750Y43500D02*
X972550D01*
Y56000D01*
X978750D01*
G01X976270Y49958D02*
X972550D01*
G01X984950Y56000D02*
Y43500D01*
X991150D01*
G01X997350Y56000D02*
Y43500D01*
X1003550D01*
G01X1010990Y56000D02*
X1014710D01*
G01X1012850D02*
Y43500D01*
G01X1010990D02*
X1014710D01*
G01X1022150D02*
Y56000D01*
X1025870D01*
X1027110Y55375D01*
X1028040Y53917D01*
X1028350Y52250D01*
X1028040Y50583D01*
X1027265Y49333D01*
X1025870Y48708D01*
X1022150D01*
G01X1034395Y45166D02*
X1035635Y44125D01*
X1037030Y43500D01*
X1038270D01*
X1039510Y44125D01*
X1040440Y45166D01*
X1040905Y46625D01*
X1040595Y48083D01*
X1039820Y49333D01*
X1038425Y50167D01*
X1036565Y50583D01*
X1035480Y51417D01*
X1035015Y52875D01*
X1035325Y54333D01*
X1036100Y55375D01*
X1037185Y56000D01*
X1038270D01*
X1039355Y55583D01*
X1040285Y54542D01*
G01X1053150Y43500D02*
X1046950D01*
Y56000D01*
X1053150D01*
G01X1050670Y49958D02*
X1046950D01*
G01X1077640Y56000D02*
Y43500D01*
G01Y45375D02*
X1077020Y44333D01*
X1076090Y43708D01*
X1075005Y43500D01*
X1073765Y43917D01*
X1072835Y44958D01*
X1072215Y46208D01*
X1072060Y47667D01*
X1072215Y49125D01*
X1072835Y50375D01*
X1073765Y51417D01*
X1075005Y51833D01*
X1076090Y51625D01*
X1076865Y51208D01*
X1077640Y50375D01*
G01X1085080Y43500D02*
Y51833D01*
G01Y50167D02*
X1085855Y51000D01*
X1086630Y51625D01*
X1087715Y51833D01*
X1088490Y51625D01*
X1089420Y51000D01*
G01X1099650Y51833D02*
Y43500D01*
G01Y55166D02*
X1099340Y55375D01*
Y55792D01*
X1099650Y56000D01*
X1099960Y55792D01*
Y55375D01*
X1099650Y55166D01*
G01X1112050Y43500D02*
Y56000D01*
G01X1124450Y43500D02*
Y56000D01*
G01X1152040D02*
Y43500D01*
G01Y45375D02*
X1151420Y44333D01*
X1150490Y43708D01*
X1149405Y43500D01*
X1148165Y43917D01*
X1147235Y44958D01*
X1146615Y46208D01*
X1146460Y47667D01*
X1146615Y49125D01*
X1147235Y50375D01*
X1148165Y51417D01*
X1149405Y51833D01*
X1150490Y51625D01*
X1151265Y51208D01*
X1152040Y50375D01*
G01X1161650Y51833D02*
Y43500D01*
G01Y55166D02*
X1161340Y55375D01*
Y55792D01*
X1161650Y56000D01*
X1161960Y55792D01*
Y55375D01*
X1161650Y55166D01*
G01X1171880Y43500D02*
Y51833D01*
G01Y50167D02*
X1172655Y51000D01*
X1173430Y51625D01*
X1174515Y51833D01*
X1175290Y51625D01*
X1176220Y51000D01*
G01X1184125Y49125D02*
X1189085D01*
X1188620Y50583D01*
X1187845Y51417D01*
X1186760Y51833D01*
X1185675Y51625D01*
X1184745Y51000D01*
X1184125Y49542D01*
X1183815Y48291D01*
Y47042D01*
X1184125Y45792D01*
X1184900Y44541D01*
X1185830Y43708D01*
X1186915Y43500D01*
X1188000Y43917D01*
X1189085Y45166D01*
G01X1201330Y50792D02*
X1200245Y51625D01*
X1199315Y51833D01*
X1198075Y51417D01*
X1197145Y50583D01*
X1196525Y49125D01*
X1196370Y47667D01*
X1196525Y46208D01*
X1197145Y44958D01*
X1198075Y43917D01*
X1199315Y43500D01*
X1200400Y43917D01*
X1201330Y44750D01*
G01X1211250Y56000D02*
Y43500D01*
G01X1209080Y51833D02*
X1213420D01*
G01X1223650D02*
Y43500D01*
G01Y55166D02*
X1223340Y55375D01*
Y55792D01*
X1223650Y56000D01*
X1223960Y55792D01*
Y55375D01*
X1223650Y55166D01*
G01X1236050Y43500D02*
X1235120Y43708D01*
X1234190Y44541D01*
X1233570Y46000D01*
X1233260Y47667D01*
X1233570Y49333D01*
X1234190Y50792D01*
X1235120Y51625D01*
X1236050Y51833D01*
X1236980Y51625D01*
X1237910Y50792D01*
X1238530Y49333D01*
X1238685Y47667D01*
X1238530Y46000D01*
X1237910Y44541D01*
X1236980Y43708D01*
X1236050Y43500D01*
G01X1245815D02*
Y51833D01*
G01Y49750D02*
X1246435Y50792D01*
X1247365Y51625D01*
X1248605Y51833D01*
X1249690Y51625D01*
X1250620Y50792D01*
X1251085Y49333D01*
Y43500D01*
G01X599000Y73500D02*
Y379500D01*
X1082600D01*
Y73500D01*
X599000D01*
G01Y101600D02*
X1082600D01*
G01X599000Y185900D02*
X1082600D01*
G01X599000Y157800D02*
X1082600D01*
G01X599000Y129700D02*
X1082600D01*
G01X599000Y270200D02*
X1082600D01*
G01X599000Y242100D02*
X1082600D01*
G01X599000Y214000D02*
X1082600D01*
G01X610005Y307650D02*
Y320150D01*
X615895D01*
G01X613725Y314108D02*
X610005D01*
G01X623490Y320150D02*
X627210D01*
G01X625350D02*
Y307650D01*
G01X623490D02*
X627210D01*
G01X638680Y313900D02*
X641780D01*
Y310150D01*
X640850Y308900D01*
X639765Y308067D01*
X638215Y307650D01*
X636665Y308067D01*
X635580Y308900D01*
X634650Y310150D01*
X634030Y311608D01*
X633720Y313275D01*
Y314733D01*
X634030Y315983D01*
X634650Y317442D01*
X635580Y318692D01*
X636510Y319525D01*
X637750Y320150D01*
X638835D01*
X640075Y319733D01*
X641005Y318900D01*
G01X646740Y320150D02*
Y311192D01*
X647360Y309316D01*
X648600Y308067D01*
X650150Y307650D01*
X651700Y308067D01*
X652940Y309316D01*
X653560Y311192D01*
Y320150D01*
G01X659450Y307650D02*
Y320150D01*
X663325D01*
X664565Y319525D01*
X665340Y318692D01*
X665650Y317025D01*
X665340Y315358D01*
X664410Y314317D01*
X663325Y313692D01*
X659450D01*
G01X663325D02*
X665650Y307650D01*
G01X678050D02*
X671850D01*
Y320150D01*
X678050D01*
G01X675570Y314108D02*
X671850D01*
G01X599000Y354500D02*
X1082600D01*
G01X599000Y326400D02*
X1082600D01*
G01X599000Y298300D02*
X1082600D01*
G01X686567Y-128617D02*
X684820Y-129200D01*
X683510Y-130659D01*
X682637Y-132408D01*
X681982Y-134742D01*
X681764Y-137367D01*
X681982Y-139992D01*
X682637Y-142326D01*
X683510Y-144076D01*
X684820Y-145534D01*
X686567Y-146117D01*
X688313Y-145534D01*
X689624Y-144076D01*
X690497Y-142326D01*
X691152Y-139992D01*
X691370Y-137367D01*
X691152Y-134742D01*
X690497Y-132408D01*
X689624Y-130659D01*
X688313Y-129200D01*
X686567Y-128617D01*
G01X699919Y-131534D02*
X701229Y-129784D01*
X702757Y-128909D01*
X704504Y-128617D01*
X706687Y-129200D01*
X708215Y-130659D01*
X708652Y-132408D01*
X708434Y-134159D01*
X707560Y-135617D01*
X703194Y-138534D01*
X701229Y-140575D01*
X699919Y-143493D01*
X699482Y-146117D01*
X708652D01*
G01X717637Y-146700D02*
X725497Y-128617D01*
G01X739067D02*
X737320Y-129200D01*
X736010Y-130659D01*
X735137Y-132408D01*
X734482Y-134742D01*
X734264Y-137367D01*
X734482Y-139992D01*
X735137Y-142326D01*
X736010Y-144076D01*
X737320Y-145534D01*
X739067Y-146117D01*
X740813Y-145534D01*
X742124Y-144076D01*
X742997Y-142326D01*
X743652Y-139992D01*
X743870Y-137367D01*
X743652Y-134742D01*
X742997Y-132408D01*
X742124Y-130659D01*
X740813Y-129200D01*
X739067Y-128617D01*
G01X756130Y-146117D02*
X756567Y-142326D01*
X757222Y-139117D01*
X758095Y-136200D01*
X759187Y-132992D01*
X760934Y-128617D01*
X752200D01*
G01X770137Y-146700D02*
X777997Y-128617D01*
G01X787419Y-131534D02*
X788729Y-129784D01*
X790257Y-128909D01*
X792004Y-128617D01*
X794187Y-129200D01*
X795715Y-130659D01*
X796152Y-132408D01*
X795934Y-134159D01*
X795060Y-135617D01*
X790694Y-138534D01*
X788729Y-140575D01*
X787419Y-143493D01*
X786982Y-146117D01*
X796152D01*
G01X809067Y-128617D02*
X807320Y-129200D01*
X806010Y-130659D01*
X805137Y-132408D01*
X804482Y-134742D01*
X804264Y-137367D01*
X804482Y-139992D01*
X805137Y-142326D01*
X806010Y-144076D01*
X807320Y-145534D01*
X809067Y-146117D01*
X810813Y-145534D01*
X812124Y-144076D01*
X812997Y-142326D01*
X813652Y-139992D01*
X813870Y-137367D01*
X813652Y-134742D01*
X812997Y-132408D01*
X812124Y-130659D01*
X810813Y-129200D01*
X809067Y-128617D01*
G01X826567Y-146117D02*
Y-128617D01*
X823947Y-132117D01*
G01Y-146117D02*
X829187D01*
G01X843630D02*
X844067Y-142326D01*
X844722Y-139117D01*
X845595Y-136200D01*
X846687Y-132992D01*
X848434Y-128617D01*
X839700D01*
G01X688900Y326400D02*
Y73500D01*
G01X682390Y360750D02*
Y373250D01*
X685490D01*
X686730Y372625D01*
X687660Y371792D01*
X688435Y370542D01*
X689055Y369083D01*
X689210Y367000D01*
X689055Y364917D01*
X688435Y363458D01*
X687660Y362208D01*
X686730Y361375D01*
X685490Y360750D01*
X682390D01*
G01X695100D02*
Y373250D01*
X698975D01*
X700215Y372625D01*
X700990Y371792D01*
X701300Y370125D01*
X700990Y368458D01*
X700060Y367417D01*
X698975Y366792D01*
X695100D01*
G01X698975D02*
X701300Y360750D01*
G01X708740Y373250D02*
X712460D01*
G01X710600D02*
Y360750D01*
G01X708740D02*
X712460D01*
G01X719900Y373250D02*
Y360750D01*
X726100D01*
G01X732300Y373250D02*
Y360750D01*
X738500D01*
G01X763610Y372208D02*
X762680Y372833D01*
X761595Y373250D01*
X760355D01*
X758960Y372625D01*
X757875Y371583D01*
X757100Y370333D01*
X756480Y368250D01*
X756325Y366375D01*
X756635Y364500D01*
X757100Y363250D01*
X758030Y362000D01*
X759115Y361167D01*
X760200Y360750D01*
X761285D01*
X762370Y361167D01*
X763300Y361791D01*
X764075Y362625D01*
G01X769345Y360750D02*
Y373250D01*
G01X775855D02*
Y360750D01*
G01Y367000D02*
X769345D01*
G01X781125Y360750D02*
X785000Y373250D01*
X788875Y360750D01*
G01X787480Y365125D02*
X782520D01*
G01X794300Y360750D02*
Y373250D01*
X798175D01*
X799415Y372625D01*
X800190Y371792D01*
X800500Y370125D01*
X800190Y368458D01*
X799260Y367417D01*
X798175Y366792D01*
X794300D01*
G01X798175D02*
X800500Y360750D01*
G01X809800Y373250D02*
Y360750D01*
G01X806235Y373250D02*
X813365D01*
G01X822200Y360333D02*
X821890Y360542D01*
Y360958D01*
X822200Y361167D01*
X822510Y360958D01*
Y360542D01*
X822200Y360333D01*
G01Y365958D02*
X821890Y366167D01*
Y366583D01*
X822200Y366792D01*
X822510Y366583D01*
Y366167D01*
X822200Y365958D01*
G01X847000Y373250D02*
Y360750D01*
G01X843435Y373250D02*
X850565D01*
G01X859400Y360750D02*
X858160Y360958D01*
X857075Y361791D01*
X856145Y363042D01*
X855525Y364500D01*
X855215Y366167D01*
Y367833D01*
X855525Y369500D01*
X856145Y370958D01*
X857075Y372208D01*
X858160Y373042D01*
X859400Y373250D01*
X860640Y373042D01*
X861725Y372208D01*
X862655Y370958D01*
X863275Y369500D01*
X863585Y367833D01*
Y366167D01*
X863275Y364500D01*
X862655Y363042D01*
X861725Y361791D01*
X860640Y360958D01*
X859400Y360750D01*
G01X868700D02*
Y373250D01*
X872420D01*
X873660Y372625D01*
X874590Y371167D01*
X874900Y369500D01*
X874590Y367833D01*
X873815Y366583D01*
X872420Y365958D01*
X868700D01*
G01X896600Y373250D02*
Y360750D01*
G01X894430Y369083D02*
X898770D01*
G01X909000Y360750D02*
X908070Y360958D01*
X907140Y361791D01*
X906520Y363250D01*
X906210Y364917D01*
X906520Y366583D01*
X907140Y368042D01*
X908070Y368875D01*
X909000Y369083D01*
X909930Y368875D01*
X910860Y368042D01*
X911480Y366583D01*
X911635Y364917D01*
X911480Y363250D01*
X910860Y361791D01*
X909930Y360958D01*
X909000Y360750D01*
G01X935040Y367417D02*
X935660Y368042D01*
X936125Y369083D01*
X936435Y370542D01*
X936125Y371792D01*
X935505Y372625D01*
X934420Y373250D01*
X930235D01*
Y360750D01*
X935350D01*
X936435Y361583D01*
X937055Y362833D01*
X937365Y364292D01*
X937055Y365750D01*
X936125Y367000D01*
X935040Y367417D01*
X930235D01*
G01X946200Y360750D02*
X944960Y360958D01*
X943875Y361791D01*
X942945Y363042D01*
X942325Y364500D01*
X942015Y366167D01*
Y367833D01*
X942325Y369500D01*
X942945Y370958D01*
X943875Y372208D01*
X944960Y373042D01*
X946200Y373250D01*
X947440Y373042D01*
X948525Y372208D01*
X949455Y370958D01*
X950075Y369500D01*
X950385Y367833D01*
Y366167D01*
X950075Y364500D01*
X949455Y363042D01*
X948525Y361791D01*
X947440Y360958D01*
X946200Y360750D01*
G01X958600Y373250D02*
Y360750D01*
G01X955035Y373250D02*
X962165D01*
G01X971000D02*
Y360750D01*
G01X967435Y373250D02*
X974565D01*
G01X983400Y360750D02*
X982160Y360958D01*
X981075Y361791D01*
X980145Y363042D01*
X979525Y364500D01*
X979215Y366167D01*
Y367833D01*
X979525Y369500D01*
X980145Y370958D01*
X981075Y372208D01*
X982160Y373042D01*
X983400Y373250D01*
X984640Y373042D01*
X985725Y372208D01*
X986655Y370958D01*
X987275Y369500D01*
X987585Y367833D01*
Y366167D01*
X987275Y364500D01*
X986655Y363042D01*
X985725Y361791D01*
X984640Y360958D01*
X983400Y360750D01*
G01X991770D02*
Y373250D01*
X995800Y362833D01*
X999830Y373250D01*
Y360750D01*
G01X734264Y-101117D02*
Y-83617D01*
X738630D01*
X740377Y-84492D01*
X741687Y-85659D01*
X742779Y-87408D01*
X743652Y-89451D01*
X743870Y-92367D01*
X743652Y-95284D01*
X742779Y-97326D01*
X741687Y-99076D01*
X740377Y-100242D01*
X738630Y-101117D01*
X734264D01*
G01X760497D02*
Y-89451D01*
G01Y-91492D02*
X759624Y-90326D01*
X758313Y-89742D01*
X756785Y-89451D01*
X755257Y-90034D01*
X753947Y-91200D01*
X753073Y-92950D01*
X752637Y-95284D01*
X753073Y-97617D01*
X753947Y-99367D01*
X755257Y-100534D01*
X756785Y-101117D01*
X758313Y-100825D01*
X759624Y-99951D01*
X760497Y-98784D01*
G01X774067Y-83617D02*
Y-101117D01*
G01X771010Y-89451D02*
X777124D01*
G01X788292Y-93242D02*
X795279D01*
X794624Y-91200D01*
X793532Y-90034D01*
X792004Y-89451D01*
X790475Y-89742D01*
X789165Y-90617D01*
X788292Y-92659D01*
X787855Y-94409D01*
Y-96159D01*
X788292Y-97909D01*
X789384Y-99659D01*
X790694Y-100825D01*
X792222Y-101117D01*
X793750Y-100534D01*
X795279Y-98784D01*
G01X758650Y109400D02*
Y121900D01*
X756790Y119400D01*
G01Y109400D02*
X760510D01*
G01X768105Y114608D02*
X769190Y116067D01*
X770120Y116900D01*
X771360Y117317D01*
X772445Y116900D01*
X773220Y116067D01*
X773840Y114817D01*
X773995Y113358D01*
X773840Y112108D01*
X773220Y110858D01*
X772290Y109817D01*
X771205Y109400D01*
X769965Y109817D01*
X768880Y111066D01*
X768260Y112942D01*
X768105Y115025D01*
X768415Y117733D01*
X768880Y119192D01*
X769655Y120650D01*
X770740Y121692D01*
X771825Y121900D01*
X772910Y121483D01*
X773685Y120442D01*
G01X780040Y111275D02*
X780970Y110233D01*
X782055Y109608D01*
X783450Y109400D01*
X784845Y109817D01*
X785930Y110650D01*
X786705Y112108D01*
X786860Y113775D01*
X786550Y115442D01*
X785775Y116483D01*
X784690Y117317D01*
X783605Y117525D01*
X782520Y117317D01*
X781125Y116483D01*
X781590Y121900D01*
X785775D01*
G01X795850Y108983D02*
X795540Y109192D01*
Y109608D01*
X795850Y109817D01*
X796160Y109608D01*
Y109192D01*
X795850Y108983D01*
G01X808250Y121900D02*
X807010Y121483D01*
X806080Y120442D01*
X805460Y119192D01*
X804995Y117525D01*
X804840Y115650D01*
X804995Y113775D01*
X805460Y112108D01*
X806080Y110858D01*
X807010Y109817D01*
X808250Y109400D01*
X809490Y109817D01*
X810420Y110858D01*
X811040Y112108D01*
X811505Y113775D01*
X811660Y115650D01*
X811505Y117525D01*
X811040Y119192D01*
X810420Y120442D01*
X809490Y121483D01*
X808250Y121900D01*
G01X735710Y81300D02*
Y93800D01*
X729975Y84842D01*
X737725D01*
G01X746250Y93800D02*
X745010Y93383D01*
X744080Y92342D01*
X743460Y91092D01*
X742995Y89425D01*
X742840Y87550D01*
X742995Y85675D01*
X743460Y84008D01*
X744080Y82758D01*
X745010Y81717D01*
X746250Y81300D01*
X747490Y81717D01*
X748420Y82758D01*
X749040Y84008D01*
X749505Y85675D01*
X749660Y87550D01*
X749505Y89425D01*
X749040Y91092D01*
X748420Y92342D01*
X747490Y93383D01*
X746250Y93800D01*
G01X758650Y80883D02*
X758340Y81092D01*
Y81508D01*
X758650Y81717D01*
X758960Y81508D01*
Y81092D01*
X758650Y80883D01*
G01X771050Y93800D02*
X769810Y93383D01*
X768880Y92342D01*
X768260Y91092D01*
X767795Y89425D01*
X767640Y87550D01*
X767795Y85675D01*
X768260Y84008D01*
X768880Y82758D01*
X769810Y81717D01*
X771050Y81300D01*
X772290Y81717D01*
X773220Y82758D01*
X773840Y84008D01*
X774305Y85675D01*
X774460Y87550D01*
X774305Y89425D01*
X773840Y91092D01*
X773220Y92342D01*
X772290Y93383D01*
X771050Y93800D01*
G01X781125Y89633D02*
X785775Y81300D01*
G01Y89633D02*
X781125Y81300D01*
G01X792905Y91717D02*
X793835Y92966D01*
X794920Y93592D01*
X796160Y93800D01*
X797710Y93383D01*
X798795Y92342D01*
X799105Y91092D01*
X798950Y89841D01*
X798330Y88800D01*
X795230Y86717D01*
X793835Y85258D01*
X792905Y83175D01*
X792595Y81300D01*
X799105D01*
G01X804840Y83800D02*
X805770Y82341D01*
X807010Y81508D01*
X808405Y81300D01*
X809645Y81508D01*
X810885Y82550D01*
X811660Y83800D01*
X811815Y85050D01*
X811505Y86508D01*
X810420Y87550D01*
X809335Y87967D01*
X807940D01*
G01X809335D02*
X810265Y88592D01*
X811040Y89633D01*
X811350Y90883D01*
X811040Y92133D01*
X810265Y93175D01*
X808870Y93800D01*
X807475Y93592D01*
X806080Y92758D01*
G01X820650Y80883D02*
X820340Y81092D01*
Y81508D01*
X820650Y81717D01*
X820960Y81508D01*
Y81092D01*
X820650Y80883D01*
G01X833050Y93800D02*
X831810Y93383D01*
X830880Y92342D01*
X830260Y91092D01*
X829795Y89425D01*
X829640Y87550D01*
X829795Y85675D01*
X830260Y84008D01*
X830880Y82758D01*
X831810Y81717D01*
X833050Y81300D01*
X834290Y81717D01*
X835220Y82758D01*
X835840Y84008D01*
X836305Y85675D01*
X836460Y87550D01*
X836305Y89425D01*
X835840Y91092D01*
X835220Y92342D01*
X834290Y93383D01*
X833050Y93800D01*
G01X761905Y204117D02*
X762835Y205366D01*
X763920Y205992D01*
X765160Y206200D01*
X766710Y205783D01*
X767795Y204742D01*
X768105Y203492D01*
X767950Y202241D01*
X767330Y201200D01*
X764230Y199117D01*
X762835Y197658D01*
X761905Y195575D01*
X761595Y193700D01*
X768105D01*
G01X774305Y198908D02*
X775390Y200367D01*
X776320Y201200D01*
X777560Y201617D01*
X778645Y201200D01*
X779420Y200367D01*
X780040Y199117D01*
X780195Y197658D01*
X780040Y196408D01*
X779420Y195158D01*
X778490Y194117D01*
X777405Y193700D01*
X776165Y194117D01*
X775080Y195366D01*
X774460Y197242D01*
X774305Y199325D01*
X774615Y202033D01*
X775080Y203492D01*
X775855Y204950D01*
X776940Y205992D01*
X778025Y206200D01*
X779110Y205783D01*
X779885Y204742D01*
G01X789650Y193283D02*
X789340Y193492D01*
Y193908D01*
X789650Y194117D01*
X789960Y193908D01*
Y193492D01*
X789650Y193283D01*
G01X802050Y206200D02*
X800810Y205783D01*
X799880Y204742D01*
X799260Y203492D01*
X798795Y201825D01*
X798640Y199950D01*
X798795Y198075D01*
X799260Y196408D01*
X799880Y195158D01*
X800810Y194117D01*
X802050Y193700D01*
X803290Y194117D01*
X804220Y195158D01*
X804840Y196408D01*
X805305Y198075D01*
X805460Y199950D01*
X805305Y201825D01*
X804840Y203492D01*
X804220Y204742D01*
X803290Y205783D01*
X802050Y206200D01*
G01X766710Y165600D02*
Y178100D01*
X760975Y169142D01*
X768725D01*
G01X777250Y178100D02*
X776010Y177683D01*
X775080Y176642D01*
X774460Y175392D01*
X773995Y173725D01*
X773840Y171850D01*
X773995Y169975D01*
X774460Y168308D01*
X775080Y167058D01*
X776010Y166017D01*
X777250Y165600D01*
X778490Y166017D01*
X779420Y167058D01*
X780040Y168308D01*
X780505Y169975D01*
X780660Y171850D01*
X780505Y173725D01*
X780040Y175392D01*
X779420Y176642D01*
X778490Y177683D01*
X777250Y178100D01*
G01X789650Y165183D02*
X789340Y165392D01*
Y165808D01*
X789650Y166017D01*
X789960Y165808D01*
Y165392D01*
X789650Y165183D01*
G01X802050Y178100D02*
X800810Y177683D01*
X799880Y176642D01*
X799260Y175392D01*
X798795Y173725D01*
X798640Y171850D01*
X798795Y169975D01*
X799260Y168308D01*
X799880Y167058D01*
X800810Y166017D01*
X802050Y165600D01*
X803290Y166017D01*
X804220Y167058D01*
X804840Y168308D01*
X805305Y169975D01*
X805460Y171850D01*
X805305Y173725D01*
X804840Y175392D01*
X804220Y176642D01*
X803290Y177683D01*
X802050Y178100D01*
G01X764850Y137500D02*
X765935Y137708D01*
X767175Y138333D01*
X767950Y139375D01*
X768260Y140833D01*
X767950Y142291D01*
X767020Y143542D01*
X765625Y144167D01*
X764075D01*
X763145Y144583D01*
X762370Y145625D01*
X762060Y147083D01*
X762525Y148542D01*
X763610Y149583D01*
X764850Y150000D01*
X766090Y149583D01*
X767175Y148542D01*
X767640Y147083D01*
X767330Y145625D01*
X766555Y144583D01*
X765625Y144167D01*
X764075D01*
X762680Y143542D01*
X761750Y142291D01*
X761440Y140833D01*
X761750Y139375D01*
X762525Y138333D01*
X763765Y137708D01*
X764850Y137500D01*
G01X774305Y142708D02*
X775390Y144167D01*
X776320Y145000D01*
X777560Y145417D01*
X778645Y145000D01*
X779420Y144167D01*
X780040Y142917D01*
X780195Y141458D01*
X780040Y140208D01*
X779420Y138958D01*
X778490Y137917D01*
X777405Y137500D01*
X776165Y137917D01*
X775080Y139166D01*
X774460Y141042D01*
X774305Y143125D01*
X774615Y145833D01*
X775080Y147292D01*
X775855Y148750D01*
X776940Y149792D01*
X778025Y150000D01*
X779110Y149583D01*
X779885Y148542D01*
G01X789650Y137083D02*
X789340Y137292D01*
Y137708D01*
X789650Y137917D01*
X789960Y137708D01*
Y137292D01*
X789650Y137083D01*
G01X802050Y150000D02*
X800810Y149583D01*
X799880Y148542D01*
X799260Y147292D01*
X798795Y145625D01*
X798640Y143750D01*
X798795Y141875D01*
X799260Y140208D01*
X799880Y138958D01*
X800810Y137917D01*
X802050Y137500D01*
X803290Y137917D01*
X804220Y138958D01*
X804840Y140208D01*
X805305Y141875D01*
X805460Y143750D01*
X805305Y145625D01*
X804840Y147292D01*
X804220Y148542D01*
X803290Y149583D01*
X802050Y150000D01*
G01X764850Y278000D02*
Y290500D01*
X762990Y288000D01*
G01Y278000D02*
X766710D01*
G01X777250Y290500D02*
X776010Y290083D01*
X775080Y289042D01*
X774460Y287792D01*
X773995Y286125D01*
X773840Y284250D01*
X773995Y282375D01*
X774460Y280708D01*
X775080Y279458D01*
X776010Y278417D01*
X777250Y278000D01*
X778490Y278417D01*
X779420Y279458D01*
X780040Y280708D01*
X780505Y282375D01*
X780660Y284250D01*
X780505Y286125D01*
X780040Y287792D01*
X779420Y289042D01*
X778490Y290083D01*
X777250Y290500D01*
G01X789650Y277583D02*
X789340Y277792D01*
Y278208D01*
X789650Y278417D01*
X789960Y278208D01*
Y277792D01*
X789650Y277583D01*
G01X802050Y290500D02*
X800810Y290083D01*
X799880Y289042D01*
X799260Y287792D01*
X798795Y286125D01*
X798640Y284250D01*
X798795Y282375D01*
X799260Y280708D01*
X799880Y279458D01*
X800810Y278417D01*
X802050Y278000D01*
X803290Y278417D01*
X804220Y279458D01*
X804840Y280708D01*
X805305Y282375D01*
X805460Y284250D01*
X805305Y286125D01*
X804840Y287792D01*
X804220Y289042D01*
X803290Y290083D01*
X802050Y290500D01*
G01X761905Y260317D02*
X762835Y261566D01*
X763920Y262192D01*
X765160Y262400D01*
X766710Y261983D01*
X767795Y260942D01*
X768105Y259692D01*
X767950Y258441D01*
X767330Y257400D01*
X764230Y255317D01*
X762835Y253858D01*
X761905Y251775D01*
X761595Y249900D01*
X768105D01*
G01X777250Y262400D02*
X776010Y261983D01*
X775080Y260942D01*
X774460Y259692D01*
X773995Y258025D01*
X773840Y256150D01*
X773995Y254275D01*
X774460Y252608D01*
X775080Y251358D01*
X776010Y250317D01*
X777250Y249900D01*
X778490Y250317D01*
X779420Y251358D01*
X780040Y252608D01*
X780505Y254275D01*
X780660Y256150D01*
X780505Y258025D01*
X780040Y259692D01*
X779420Y260942D01*
X778490Y261983D01*
X777250Y262400D01*
G01X789650Y249483D02*
X789340Y249692D01*
Y250108D01*
X789650Y250317D01*
X789960Y250108D01*
Y249692D01*
X789650Y249483D01*
G01X802050Y262400D02*
X800810Y261983D01*
X799880Y260942D01*
X799260Y259692D01*
X798795Y258025D01*
X798640Y256150D01*
X798795Y254275D01*
X799260Y252608D01*
X799880Y251358D01*
X800810Y250317D01*
X802050Y249900D01*
X803290Y250317D01*
X804220Y251358D01*
X804840Y252608D01*
X805305Y254275D01*
X805460Y256150D01*
X805305Y258025D01*
X804840Y259692D01*
X804220Y260942D01*
X803290Y261983D01*
X802050Y262400D01*
G01X761905Y232217D02*
X762835Y233466D01*
X763920Y234092D01*
X765160Y234300D01*
X766710Y233883D01*
X767795Y232842D01*
X768105Y231592D01*
X767950Y230341D01*
X767330Y229300D01*
X764230Y227217D01*
X762835Y225758D01*
X761905Y223675D01*
X761595Y221800D01*
X768105D01*
G01X777250D02*
X778335Y222008D01*
X779575Y222633D01*
X780350Y223675D01*
X780660Y225133D01*
X780350Y226591D01*
X779420Y227842D01*
X778025Y228467D01*
X776475D01*
X775545Y228883D01*
X774770Y229925D01*
X774460Y231383D01*
X774925Y232842D01*
X776010Y233883D01*
X777250Y234300D01*
X778490Y233883D01*
X779575Y232842D01*
X780040Y231383D01*
X779730Y229925D01*
X778955Y228883D01*
X778025Y228467D01*
X776475D01*
X775080Y227842D01*
X774150Y226591D01*
X773840Y225133D01*
X774150Y223675D01*
X774925Y222633D01*
X776165Y222008D01*
X777250Y221800D01*
G01X789650Y221383D02*
X789340Y221592D01*
Y222008D01*
X789650Y222217D01*
X789960Y222008D01*
Y221592D01*
X789650Y221383D01*
G01X802050Y234300D02*
X800810Y233883D01*
X799880Y232842D01*
X799260Y231592D01*
X798795Y229925D01*
X798640Y228050D01*
X798795Y226175D01*
X799260Y224508D01*
X799880Y223258D01*
X800810Y222217D01*
X802050Y221800D01*
X803290Y222217D01*
X804220Y223258D01*
X804840Y224508D01*
X805305Y226175D01*
X805460Y228050D01*
X805305Y229925D01*
X804840Y231592D01*
X804220Y232842D01*
X803290Y233883D01*
X802050Y234300D01*
G01X712925Y335750D02*
X716800Y348250D01*
X720675Y335750D01*
G01X719280Y340125D02*
X714320D01*
G01X726100Y348250D02*
Y335750D01*
X732300D01*
G01X738500Y348250D02*
Y335750D01*
X744700D01*
G01X762990Y348250D02*
Y339292D01*
X763610Y337416D01*
X764850Y336167D01*
X766400Y335750D01*
X767950Y336167D01*
X769190Y337416D01*
X769810Y339292D01*
Y348250D01*
G01X775235Y335750D02*
Y348250D01*
X782365Y335750D01*
Y348250D01*
G01X789340D02*
X793060D01*
G01X791200D02*
Y335750D01*
G01X789340D02*
X793060D01*
G01X803600Y348250D02*
Y335750D01*
G01X800035Y348250D02*
X807165D01*
G01X812745Y337416D02*
X813985Y336375D01*
X815380Y335750D01*
X816620D01*
X817860Y336375D01*
X818790Y337416D01*
X819255Y338875D01*
X818945Y340333D01*
X818170Y341583D01*
X816775Y342417D01*
X814915Y342833D01*
X813830Y343667D01*
X813365Y345125D01*
X813675Y346583D01*
X814450Y347625D01*
X815535Y348250D01*
X816620D01*
X817705Y347833D01*
X818635Y346792D01*
G01X836925Y335750D02*
X840800Y348250D01*
X844675Y335750D01*
G01X843280Y340125D02*
X838320D01*
G01X850100Y335750D02*
Y348250D01*
X853975D01*
X855215Y347625D01*
X855990Y346792D01*
X856300Y345125D01*
X855990Y343458D01*
X855060Y342417D01*
X853975Y341792D01*
X850100D01*
G01X853975D02*
X856300Y335750D01*
G01X868700D02*
X862500D01*
Y348250D01*
X868700D01*
G01X866220Y342208D02*
X862500D01*
G01X888540Y348250D02*
X892260D01*
G01X890400D02*
Y335750D01*
G01X888540D02*
X892260D01*
G01X899235D02*
Y348250D01*
X906365Y335750D01*
Y348250D01*
G01X923570Y335750D02*
Y348250D01*
X927600Y337833D01*
X931630Y348250D01*
Y335750D01*
G01X938140Y348250D02*
X941860D01*
G01X940000D02*
Y335750D01*
G01X938140D02*
X941860D01*
G01X949300Y348250D02*
Y335750D01*
X955500D01*
G01X961545Y337416D02*
X962785Y336375D01*
X964180Y335750D01*
X965420D01*
X966660Y336375D01*
X967590Y337416D01*
X968055Y338875D01*
X967745Y340333D01*
X966970Y341583D01*
X965575Y342417D01*
X963715Y342833D01*
X962630Y343667D01*
X962165Y345125D01*
X962475Y346583D01*
X963250Y347625D01*
X964335Y348250D01*
X965420D01*
X966505Y347833D01*
X967435Y346792D01*
G01X761595Y309316D02*
X762835Y308275D01*
X764230Y307650D01*
X765470D01*
X766710Y308275D01*
X767640Y309316D01*
X768105Y310775D01*
X767795Y312233D01*
X767020Y313483D01*
X765625Y314317D01*
X763765Y314733D01*
X762680Y315567D01*
X762215Y317025D01*
X762525Y318483D01*
X763300Y319525D01*
X764385Y320150D01*
X765470D01*
X766555Y319733D01*
X767485Y318692D01*
G01X775390Y320150D02*
X779110D01*
G01X777250D02*
Y307650D01*
G01X775390D02*
X779110D01*
G01X786705Y320150D02*
X792595D01*
X786705Y307650D01*
X792595D01*
G01X805150D02*
X798950D01*
Y320150D01*
X805150D01*
G01X802670Y314108D02*
X798950D01*
G01X882185Y109400D02*
Y121900D01*
X889315Y109400D01*
Y121900D01*
G01X898150Y109400D02*
X896910Y109608D01*
X895825Y110441D01*
X894895Y111692D01*
X894275Y113150D01*
X893965Y114817D01*
Y116483D01*
X894275Y118150D01*
X894895Y119608D01*
X895825Y120858D01*
X896910Y121692D01*
X898150Y121900D01*
X899390Y121692D01*
X900475Y120858D01*
X901405Y119608D01*
X902025Y118150D01*
X902335Y116483D01*
Y114817D01*
X902025Y113150D01*
X901405Y111692D01*
X900475Y110441D01*
X899390Y109608D01*
X898150Y109400D01*
G01X906985D02*
Y121900D01*
X914115Y109400D01*
Y121900D01*
G01X920935Y113567D02*
X924965D01*
G01X932250Y109400D02*
Y121900D01*
X935970D01*
X937210Y121275D01*
X938140Y119817D01*
X938450Y118150D01*
X938140Y116483D01*
X937365Y115233D01*
X935970Y114608D01*
X932250D01*
G01X944650Y121900D02*
Y109400D01*
X950850D01*
G01X956275D02*
X960150Y121900D01*
X964025Y109400D01*
G01X962630Y113775D02*
X957670D01*
G01X972550Y121900D02*
Y109400D01*
G01X968985Y121900D02*
X976115D01*
G01X988050Y109400D02*
X981850D01*
Y121900D01*
X988050D01*
G01X985570Y115858D02*
X981850D01*
G01X993940Y109400D02*
Y121900D01*
X997040D01*
X998280Y121275D01*
X999210Y120442D01*
X999985Y119192D01*
X1000605Y117733D01*
X1000760Y115650D01*
X1000605Y113567D01*
X999985Y112108D01*
X999210Y110858D01*
X998280Y110025D01*
X997040Y109400D01*
X993940D01*
G01X882185Y81300D02*
Y93800D01*
X889315Y81300D01*
Y93800D01*
G01X898150Y81300D02*
X896910Y81508D01*
X895825Y82341D01*
X894895Y83592D01*
X894275Y85050D01*
X893965Y86717D01*
Y88383D01*
X894275Y90050D01*
X894895Y91508D01*
X895825Y92758D01*
X896910Y93592D01*
X898150Y93800D01*
X899390Y93592D01*
X900475Y92758D01*
X901405Y91508D01*
X902025Y90050D01*
X902335Y88383D01*
Y86717D01*
X902025Y85050D01*
X901405Y83592D01*
X900475Y82341D01*
X899390Y81508D01*
X898150Y81300D01*
G01X906985D02*
Y93800D01*
X914115Y81300D01*
Y93800D01*
G01X920935Y85467D02*
X924965D01*
G01X932250Y81300D02*
Y93800D01*
X935970D01*
X937210Y93175D01*
X938140Y91717D01*
X938450Y90050D01*
X938140Y88383D01*
X937365Y87133D01*
X935970Y86508D01*
X932250D01*
G01X944650Y93800D02*
Y81300D01*
X950850D01*
G01X956275D02*
X960150Y93800D01*
X964025Y81300D01*
G01X962630Y85675D02*
X957670D01*
G01X972550Y93800D02*
Y81300D01*
G01X968985Y93800D02*
X976115D01*
G01X988050Y81300D02*
X981850D01*
Y93800D01*
X988050D01*
G01X985570Y87758D02*
X981850D01*
G01X993940Y81300D02*
Y93800D01*
X997040D01*
X998280Y93175D01*
X999210Y92342D01*
X999985Y91092D01*
X1000605Y89633D01*
X1000760Y87550D01*
X1000605Y85467D01*
X999985Y84008D01*
X999210Y82758D01*
X998280Y81925D01*
X997040Y81300D01*
X993940D01*
G01X878000Y326400D02*
Y73500D01*
G01X882185Y193700D02*
Y206200D01*
X889315Y193700D01*
Y206200D01*
G01X898150Y193700D02*
X896910Y193908D01*
X895825Y194741D01*
X894895Y195992D01*
X894275Y197450D01*
X893965Y199117D01*
Y200783D01*
X894275Y202450D01*
X894895Y203908D01*
X895825Y205158D01*
X896910Y205992D01*
X898150Y206200D01*
X899390Y205992D01*
X900475Y205158D01*
X901405Y203908D01*
X902025Y202450D01*
X902335Y200783D01*
Y199117D01*
X902025Y197450D01*
X901405Y195992D01*
X900475Y194741D01*
X899390Y193908D01*
X898150Y193700D01*
G01X906985D02*
Y206200D01*
X914115Y193700D01*
Y206200D01*
G01X920935Y197867D02*
X924965D01*
G01X932250Y193700D02*
Y206200D01*
X935970D01*
X937210Y205575D01*
X938140Y204117D01*
X938450Y202450D01*
X938140Y200783D01*
X937365Y199533D01*
X935970Y198908D01*
X932250D01*
G01X944650Y206200D02*
Y193700D01*
X950850D01*
G01X956275D02*
X960150Y206200D01*
X964025Y193700D01*
G01X962630Y198075D02*
X957670D01*
G01X972550Y206200D02*
Y193700D01*
G01X968985Y206200D02*
X976115D01*
G01X988050Y193700D02*
X981850D01*
Y206200D01*
X988050D01*
G01X985570Y200158D02*
X981850D01*
G01X993940Y193700D02*
Y206200D01*
X997040D01*
X998280Y205575D01*
X999210Y204742D01*
X999985Y203492D01*
X1000605Y202033D01*
X1000760Y199950D01*
X1000605Y197867D01*
X999985Y196408D01*
X999210Y195158D01*
X998280Y194325D01*
X997040Y193700D01*
X993940D01*
G01X882185Y165600D02*
Y178100D01*
X889315Y165600D01*
Y178100D01*
G01X898150Y165600D02*
X896910Y165808D01*
X895825Y166641D01*
X894895Y167892D01*
X894275Y169350D01*
X893965Y171017D01*
Y172683D01*
X894275Y174350D01*
X894895Y175808D01*
X895825Y177058D01*
X896910Y177892D01*
X898150Y178100D01*
X899390Y177892D01*
X900475Y177058D01*
X901405Y175808D01*
X902025Y174350D01*
X902335Y172683D01*
Y171017D01*
X902025Y169350D01*
X901405Y167892D01*
X900475Y166641D01*
X899390Y165808D01*
X898150Y165600D01*
G01X906985D02*
Y178100D01*
X914115Y165600D01*
Y178100D01*
G01X920935Y169767D02*
X924965D01*
G01X932250Y165600D02*
Y178100D01*
X935970D01*
X937210Y177475D01*
X938140Y176017D01*
X938450Y174350D01*
X938140Y172683D01*
X937365Y171433D01*
X935970Y170808D01*
X932250D01*
G01X944650Y178100D02*
Y165600D01*
X950850D01*
G01X956275D02*
X960150Y178100D01*
X964025Y165600D01*
G01X962630Y169975D02*
X957670D01*
G01X972550Y178100D02*
Y165600D01*
G01X968985Y178100D02*
X976115D01*
G01X988050Y165600D02*
X981850D01*
Y178100D01*
X988050D01*
G01X985570Y172058D02*
X981850D01*
G01X993940Y165600D02*
Y178100D01*
X997040D01*
X998280Y177475D01*
X999210Y176642D01*
X999985Y175392D01*
X1000605Y173933D01*
X1000760Y171850D01*
X1000605Y169767D01*
X999985Y168308D01*
X999210Y167058D01*
X998280Y166225D01*
X997040Y165600D01*
X993940D01*
G01X882185Y137500D02*
Y150000D01*
X889315Y137500D01*
Y150000D01*
G01X898150Y137500D02*
X896910Y137708D01*
X895825Y138541D01*
X894895Y139792D01*
X894275Y141250D01*
X893965Y142917D01*
Y144583D01*
X894275Y146250D01*
X894895Y147708D01*
X895825Y148958D01*
X896910Y149792D01*
X898150Y150000D01*
X899390Y149792D01*
X900475Y148958D01*
X901405Y147708D01*
X902025Y146250D01*
X902335Y144583D01*
Y142917D01*
X902025Y141250D01*
X901405Y139792D01*
X900475Y138541D01*
X899390Y137708D01*
X898150Y137500D01*
G01X906985D02*
Y150000D01*
X914115Y137500D01*
Y150000D01*
G01X920935Y141667D02*
X924965D01*
G01X932250Y137500D02*
Y150000D01*
X935970D01*
X937210Y149375D01*
X938140Y147917D01*
X938450Y146250D01*
X938140Y144583D01*
X937365Y143333D01*
X935970Y142708D01*
X932250D01*
G01X944650Y150000D02*
Y137500D01*
X950850D01*
G01X956275D02*
X960150Y150000D01*
X964025Y137500D01*
G01X962630Y141875D02*
X957670D01*
G01X972550Y150000D02*
Y137500D01*
G01X968985Y150000D02*
X976115D01*
G01X988050Y137500D02*
X981850D01*
Y150000D01*
X988050D01*
G01X985570Y143958D02*
X981850D01*
G01X993940Y137500D02*
Y150000D01*
X997040D01*
X998280Y149375D01*
X999210Y148542D01*
X999985Y147292D01*
X1000605Y145833D01*
X1000760Y143750D01*
X1000605Y141667D01*
X999985Y140208D01*
X999210Y138958D01*
X998280Y138125D01*
X997040Y137500D01*
X993940D01*
G01X907450Y278000D02*
Y290500D01*
X911170D01*
X912410Y289875D01*
X913340Y288417D01*
X913650Y286750D01*
X913340Y285083D01*
X912565Y283833D01*
X911170Y283208D01*
X907450D01*
G01X919850Y290500D02*
Y278000D01*
X926050D01*
G01X931475D02*
X935350Y290500D01*
X939225Y278000D01*
G01X937830Y282375D02*
X932870D01*
G01X947750Y290500D02*
Y278000D01*
G01X944185Y290500D02*
X951315D01*
G01X963250Y278000D02*
X957050D01*
Y290500D01*
X963250D01*
G01X960770Y284458D02*
X957050D01*
G01X969140Y278000D02*
Y290500D01*
X972240D01*
X973480Y289875D01*
X974410Y289042D01*
X975185Y287792D01*
X975805Y286333D01*
X975960Y284250D01*
X975805Y282167D01*
X975185Y280708D01*
X974410Y279458D01*
X973480Y278625D01*
X972240Y278000D01*
X969140D01*
G01X907450Y249900D02*
Y262400D01*
X911170D01*
X912410Y261775D01*
X913340Y260317D01*
X913650Y258650D01*
X913340Y256983D01*
X912565Y255733D01*
X911170Y255108D01*
X907450D01*
G01X919850Y262400D02*
Y249900D01*
X926050D01*
G01X931475D02*
X935350Y262400D01*
X939225Y249900D01*
G01X937830Y254275D02*
X932870D01*
G01X947750Y262400D02*
Y249900D01*
G01X944185Y262400D02*
X951315D01*
G01X963250Y249900D02*
X957050D01*
Y262400D01*
X963250D01*
G01X960770Y256358D02*
X957050D01*
G01X969140Y249900D02*
Y262400D01*
X972240D01*
X973480Y261775D01*
X974410Y260942D01*
X975185Y259692D01*
X975805Y258233D01*
X975960Y256150D01*
X975805Y254067D01*
X975185Y252608D01*
X974410Y251358D01*
X973480Y250525D01*
X972240Y249900D01*
X969140D01*
G01X907450Y221800D02*
Y234300D01*
X911170D01*
X912410Y233675D01*
X913340Y232217D01*
X913650Y230550D01*
X913340Y228883D01*
X912565Y227633D01*
X911170Y227008D01*
X907450D01*
G01X919850Y234300D02*
Y221800D01*
X926050D01*
G01X931475D02*
X935350Y234300D01*
X939225Y221800D01*
G01X937830Y226175D02*
X932870D01*
G01X947750Y234300D02*
Y221800D01*
G01X944185Y234300D02*
X951315D01*
G01X963250Y221800D02*
X957050D01*
Y234300D01*
X963250D01*
G01X960770Y228258D02*
X957050D01*
G01X969140Y221800D02*
Y234300D01*
X972240D01*
X973480Y233675D01*
X974410Y232842D01*
X975185Y231592D01*
X975805Y230133D01*
X975960Y228050D01*
X975805Y225967D01*
X975185Y224508D01*
X974410Y223258D01*
X973480Y222425D01*
X972240Y221800D01*
X969140D01*
G01X907450Y307650D02*
Y320150D01*
X911170D01*
X912410Y319525D01*
X913340Y318067D01*
X913650Y316400D01*
X913340Y314733D01*
X912565Y313483D01*
X911170Y312858D01*
X907450D01*
G01X919850Y320150D02*
Y307650D01*
X926050D01*
G01X931475D02*
X935350Y320150D01*
X939225Y307650D01*
G01X937830Y312025D02*
X932870D01*
G01X947750Y320150D02*
Y307650D01*
G01X944185Y320150D02*
X951315D01*
G01X963250Y307650D02*
X957050D01*
Y320150D01*
X963250D01*
G01X960770Y314108D02*
X957050D01*
G01X969140Y307650D02*
Y320150D01*
X972240D01*
X973480Y319525D01*
X974410Y318692D01*
X975185Y317442D01*
X975805Y315983D01*
X975960Y313900D01*
X975805Y311817D01*
X975185Y310358D01*
X974410Y309108D01*
X973480Y308275D01*
X972240Y307650D01*
X969140D01*
G01X1005100Y326400D02*
Y73500D01*
G01X1040905Y119817D02*
X1041835Y121066D01*
X1042920Y121692D01*
X1044160Y121900D01*
X1045710Y121483D01*
X1046795Y120442D01*
X1047105Y119192D01*
X1046950Y117941D01*
X1046330Y116900D01*
X1043230Y114817D01*
X1041835Y113358D01*
X1040905Y111275D01*
X1040595Y109400D01*
X1047105D01*
G01X1043850Y81300D02*
Y93800D01*
X1041990Y91300D01*
G01Y81300D02*
X1045710D01*
G01X1043850Y193700D02*
Y206200D01*
X1041990Y203700D01*
G01Y193700D02*
X1045710D01*
G01X1040905Y176017D02*
X1041835Y177266D01*
X1042920Y177892D01*
X1044160Y178100D01*
X1045710Y177683D01*
X1046795Y176642D01*
X1047105Y175392D01*
X1046950Y174141D01*
X1046330Y173100D01*
X1043230Y171017D01*
X1041835Y169558D01*
X1040905Y167475D01*
X1040595Y165600D01*
X1047105D01*
G01X1040905Y147917D02*
X1041835Y149166D01*
X1042920Y149792D01*
X1044160Y150000D01*
X1045710Y149583D01*
X1046795Y148542D01*
X1047105Y147292D01*
X1046950Y146041D01*
X1046330Y145000D01*
X1043230Y142917D01*
X1041835Y141458D01*
X1040905Y139375D01*
X1040595Y137500D01*
X1047105D01*
G01X1037340Y278000D02*
X1037650Y280708D01*
X1038115Y283000D01*
X1038735Y285083D01*
X1039510Y287375D01*
X1040750Y290500D01*
X1034550D01*
G01X1047105Y283208D02*
X1048190Y284667D01*
X1049120Y285500D01*
X1050360Y285917D01*
X1051445Y285500D01*
X1052220Y284667D01*
X1052840Y283417D01*
X1052995Y281958D01*
X1052840Y280708D01*
X1052220Y279458D01*
X1051290Y278417D01*
X1050205Y278000D01*
X1048965Y278417D01*
X1047880Y279666D01*
X1047260Y281542D01*
X1047105Y283625D01*
X1047415Y286333D01*
X1047880Y287792D01*
X1048655Y289250D01*
X1049740Y290292D01*
X1050825Y290500D01*
X1051910Y290083D01*
X1052685Y289042D01*
G01X1037650Y249900D02*
Y262400D01*
X1035790Y259900D01*
G01Y249900D02*
X1039510D01*
G01X1047105Y255108D02*
X1048190Y256567D01*
X1049120Y257400D01*
X1050360Y257817D01*
X1051445Y257400D01*
X1052220Y256567D01*
X1052840Y255317D01*
X1052995Y253858D01*
X1052840Y252608D01*
X1052220Y251358D01*
X1051290Y250317D01*
X1050205Y249900D01*
X1048965Y250317D01*
X1047880Y251566D01*
X1047260Y253442D01*
X1047105Y255525D01*
X1047415Y258233D01*
X1047880Y259692D01*
X1048655Y261150D01*
X1049740Y262192D01*
X1050825Y262400D01*
X1051910Y261983D01*
X1052685Y260942D01*
G01X1045710Y221800D02*
Y234300D01*
X1039975Y225342D01*
X1047725D01*
G01X1031450Y307650D02*
X1030210Y307858D01*
X1029125Y308691D01*
X1028195Y309942D01*
X1027575Y311400D01*
X1027265Y313067D01*
Y314733D01*
X1027575Y316400D01*
X1028195Y317858D01*
X1029125Y319108D01*
X1030210Y319942D01*
X1031450Y320150D01*
X1032690Y319942D01*
X1033775Y319108D01*
X1034705Y317858D01*
X1035325Y316400D01*
X1035635Y314733D01*
Y313067D01*
X1035325Y311400D01*
X1034705Y309942D01*
X1033775Y308691D01*
X1032690Y307858D01*
X1031450Y307650D01*
G01X1032690Y310983D02*
X1034550Y307650D01*
G01X1043850Y320150D02*
Y307650D01*
G01X1040285Y320150D02*
X1047415D01*
G01X1056250Y307650D02*
Y313275D01*
X1053150Y320150D01*
G01X1059350D02*
X1056250Y313275D01*
G01X0Y-11811D02*
G03X7874Y-19685I7874J0D01*
G01X37008Y0D02*
G03Y-7874I0J-3937D01*
G01X11811D02*
G03Y0I0J3937D01*
G01X0Y-7874D02*
Y-11811D01*
G01X7874Y-19685D02*
X181690D01*
G01X0Y-7874D02*
X11811D01*
G01X25985Y19685D02*
G03X9449I-8268J0D01*
G01D02*
G03X25985I8268J0D01*
G01D02*
G03X9449I-8268J0D01*
G01D02*
G03X25985I8268J0D01*
G01D02*
G03X9449I-8268J0D01*
G01D02*
G03X25985I8268J0D01*
G01D02*
G03X9449I-8268J0D01*
G01D02*
G03X25985I8268J0D01*
G01X9449D02*
G03X25985I8268J0D01*
G01D02*
G03X9449I-8268J0D01*
G01D02*
G03X25985I8268J0D01*
G01D02*
G03X9449I-8268J0D01*
G01X3937Y0D02*
X173229D01*
G01X0Y3937D02*
G03X3937Y0I3937J0D01*
G01X0Y57874D02*
Y3937D01*
G01X37008Y69685D02*
G03Y61811I0J-3937D01*
G01X11811D02*
G03Y69685I0J3937D01*
G01X25985Y89370D02*
G03X9449I-8268J0D01*
G01D02*
G03X25985I8268J0D01*
G01D02*
G03X9449I-8268J0D01*
G01D02*
G03X25985I8268J0D01*
G01D02*
G03X9449I-8268J0D01*
G01D02*
G03X25985I8268J0D01*
G01D02*
G03X9449I-8268J0D01*
G01D02*
G03X25985I8268J0D01*
G01X9449D02*
G03X25985I8268J0D01*
G01D02*
G03X9449I-8268J0D01*
G01D02*
G03X25985I8268J0D01*
G01D02*
G03X9449I-8268J0D01*
G01X3937Y69685D02*
X173229D01*
G01X0Y73622D02*
G03X3937Y69685I3937J0D01*
G01X0Y127559D02*
Y73622D01*
G01X3937Y61811D02*
G03X0Y57874I0J-3937D01*
G01X173229Y61811D02*
X3937D01*
G01X37008Y139370D02*
G03Y131496I0J-3937D01*
G01X11811D02*
G03Y139370I0J3937D01*
G01X25985Y159055D02*
G03X9449I-8268J0D01*
G01D02*
G03X25985I8268J0D01*
G01D02*
G03X9449I-8268J0D01*
G01D02*
G03X25985I8268J0D01*
G01D02*
G03X9449I-8268J0D01*
G01D02*
G03X25985I8268J0D01*
G01D02*
G03X9449I-8268J0D01*
G01D02*
G03X25985I8268J0D01*
G01X9449D02*
G03X25985I8268J0D01*
G01D02*
G03X9449I-8268J0D01*
G01D02*
G03X25985I8268J0D01*
G01D02*
G03X9449I-8268J0D01*
G01X3937Y139370D02*
X173229D01*
G01X0Y143307D02*
G03X3937Y139370I3937J0D01*
G01X0Y197244D02*
Y143307D01*
G01X3937Y131496D02*
G03X0Y127559I0J-3937D01*
G01X173229Y131496D02*
X3937D01*
G01X37008Y278740D02*
G03Y270866I0J-3937D01*
G01X11811D02*
G03Y278740I0J3937D01*
G01X37008Y209055D02*
G03Y201181I0J-3937D01*
G01X11811D02*
G03Y209055I0J3937D01*
G01X3937Y278740D02*
X173229D01*
G01X0Y282677D02*
G03X3937Y278740I3937J0D01*
G01X25985Y228740D02*
G03X9449I-8268J0D01*
G01D02*
G03X25985I8268J0D01*
G01D02*
G03X9449I-8268J0D01*
G01D02*
G03X25985I8268J0D01*
G01D02*
G03X9449I-8268J0D01*
G01D02*
G03X25985I8268J0D01*
G01D02*
G03X9449I-8268J0D01*
G01D02*
G03X25985I8268J0D01*
G01X9449D02*
G03X25985I8268J0D01*
G01D02*
G03X9449I-8268J0D01*
G01D02*
G03X25985I8268J0D01*
G01D02*
G03X9449I-8268J0D01*
G01X3937Y209055D02*
X173229D01*
G01X0Y212992D02*
G03X3937Y209055I3937J0D01*
G01X0Y266929D02*
Y212992D01*
G01X3937Y270866D02*
G03X0Y266929I0J-3937D01*
G01X173229Y270866D02*
X3937D01*
G01Y201181D02*
G03X0Y197244I0J-3937D01*
G01X173229Y201181D02*
X3937D01*
G01X37008Y348425D02*
G03Y340551I0J-3937D01*
G01X11811D02*
G03Y348425I0J3937D01*
G01X9449Y368110D02*
G03X25985I8268J0D01*
G01X9449D02*
G03X25985I8268J0D01*
G01X9449D02*
G03X25985I8268J0D01*
G01X9449D02*
G03X25985I8268J0D01*
G01X9449D02*
G03X25985I8268J0D01*
G01X9449D02*
G03X25985I8268J0D01*
G01X3937Y348425D02*
X173229D01*
G01X0Y352362D02*
G03X3937Y348425I3937J0D01*
G01X0Y406299D02*
Y352362D01*
G01X25985Y298425D02*
G03X9449I-8268J0D01*
G01D02*
G03X25985I8268J0D01*
G01D02*
G03X9449I-8268J0D01*
G01D02*
G03X25985I8268J0D01*
G01D02*
G03X9449I-8268J0D01*
G01D02*
G03X25985I8268J0D01*
G01D02*
G03X9449I-8268J0D01*
G01D02*
G03X25985I8268J0D01*
G01X9449D02*
G03X25985I8268J0D01*
G01D02*
G03X9449I-8268J0D01*
G01D02*
G03X25985I8268J0D01*
G01D02*
G03X9449I-8268J0D01*
G01X0Y336614D02*
Y282677D01*
G01X3937Y340551D02*
G03X0Y336614I0J-3937D01*
G01X173229Y340551D02*
X3937D01*
G01X37008Y418110D02*
G03Y410236I0J-3937D01*
G01X11811D02*
G03Y418110I0J3937D01*
G01X25985Y437795D02*
G03X9449I-8268J0D01*
G01D02*
G03X25985I8268J0D01*
G01D02*
G03X9449I-8268J0D01*
G01D02*
G03X25985I8268J0D01*
G01D02*
G03X9449I-8268J0D01*
G01D02*
G03X25985I8268J0D01*
G01D02*
G03X9449I-8268J0D01*
G01D02*
G03X25985I8268J0D01*
G01X9449D02*
G03X25985I8268J0D01*
G01D02*
G03X9449I-8268J0D01*
G01D02*
G03X25985I8268J0D01*
G01D02*
G03X9449I-8268J0D01*
G01X3937Y418110D02*
X173229D01*
G01X0Y422047D02*
G03X3937Y418110I3937J0D01*
G01X0Y475984D02*
Y422047D01*
G01X25985Y368110D02*
G03X9449I-8268J0D01*
G01X25985D02*
G03X9449I-8268J0D01*
G01X25985D02*
G03X9449I-8268J0D01*
G01X25985D02*
G03X9449I-8268J0D01*
G01X25985D02*
G03X9449I-8268J0D01*
G01X25985D02*
G03X9449I-8268J0D01*
G01X3937Y410236D02*
G03X0Y406299I0J-3937D01*
G01X173229Y410236D02*
X3937D01*
G01X37008Y487795D02*
G03Y479921I0J-3937D01*
G01X11811D02*
G03Y487795I0J3937D01*
G01X25985Y507480D02*
G03X9449I-8268J0D01*
G01D02*
G03X25985I8268J0D01*
G01D02*
G03X9449I-8268J0D01*
G01D02*
G03X25985I8268J0D01*
G01D02*
G03X9449I-8268J0D01*
G01D02*
G03X25985I8268J0D01*
G01D02*
G03X9449I-8268J0D01*
G01D02*
G03X25985I8268J0D01*
G01X9449D02*
G03X25985I8268J0D01*
G01D02*
G03X9449I-8268J0D01*
G01D02*
G03X25985I8268J0D01*
G01D02*
G03X9449I-8268J0D01*
G01X3937Y487795D02*
X173229D01*
G01X0Y491732D02*
G03X3937Y487795I3937J0D01*
G01X0Y545669D02*
Y491732D01*
G01X3937Y479921D02*
G03X0Y475984I0J-3937D01*
G01X173229Y479921D02*
X3937D01*
G01X37008Y557480D02*
G03Y549606I0J-3937D01*
G01X11811D02*
G03Y557480I0J3937D01*
G01X25985Y577165D02*
G03X9449I-8268J0D01*
G01D02*
G03X25985I8268J0D01*
G01D02*
G03X9449I-8268J0D01*
G01D02*
G03X25985I8268J0D01*
G01D02*
G03X9449I-8268J0D01*
G01D02*
G03X25985I8268J0D01*
G01D02*
G03X9449I-8268J0D01*
G01D02*
G03X25985I8268J0D01*
G01X9449D02*
G03X25985I8268J0D01*
G01D02*
G03X9449I-8268J0D01*
G01D02*
G03X25985I8268J0D01*
G01D02*
G03X9449I-8268J0D01*
G01X3937Y557480D02*
X173229D01*
G01X0Y561417D02*
G03X3937Y557480I3937J0D01*
G01X0Y615354D02*
Y561417D01*
G01X3937Y549606D02*
G03X0Y545669I0J-3937D01*
G01X173229Y549606D02*
X3937D01*
G01X37008Y627165D02*
G03Y619291I0J-3937D01*
G01X11811D02*
G03Y627165I0J3937D01*
G01X25985Y646850D02*
G03X9449I-8268J0D01*
G01D02*
G03X25985I8268J0D01*
G01D02*
G03X9449I-8268J0D01*
G01D02*
G03X25985I8268J0D01*
G01D02*
G03X9449I-8268J0D01*
G01D02*
G03X25985I8268J0D01*
G01D02*
G03X9449I-8268J0D01*
G01D02*
G03X25985I8268J0D01*
G01X9449D02*
G03X25985I8268J0D01*
G01D02*
G03X9449I-8268J0D01*
G01D02*
G03X25985I8268J0D01*
G01D02*
G03X9449I-8268J0D01*
G01X3937Y627165D02*
X173229D01*
G01X0Y631102D02*
G03X3937Y627165I3937J0D01*
G01X0Y685039D02*
Y631102D01*
G01X3937Y688976D02*
G03X0Y685039I0J-3937D01*
G01X173229Y688976D02*
X3937D01*
G01Y619291D02*
G03X0Y615354I0J-3937D01*
G01X173229Y619291D02*
X3937D01*
G01X37008Y-7874D02*
X140158D01*
G01X67903Y39475D02*
X63903D01*
X66770Y37008D01*
Y40342D01*
G01X63903Y43275D02*
X64036Y42742D01*
X64370Y42342D01*
X64770Y42075D01*
X65303Y41875D01*
X65903Y41808D01*
X66503Y41875D01*
X67036Y42075D01*
X67436Y42342D01*
X67770Y42742D01*
X67903Y43275D01*
X67770Y43808D01*
X67436Y44208D01*
X67036Y44475D01*
X66503Y44675D01*
X65903Y44742D01*
X65303Y44675D01*
X64770Y44475D01*
X64370Y44208D01*
X64036Y43808D01*
X63903Y43275D01*
G01X67903Y46475D02*
X63903Y49275D01*
G01Y46475D02*
X67903Y49275D01*
G01X64570Y51208D02*
X64170Y51608D01*
X63970Y52075D01*
X63903Y52608D01*
X64036Y53275D01*
X64370Y53742D01*
X64770Y53875D01*
X65170Y53808D01*
X65503Y53542D01*
X66170Y52208D01*
X66636Y51608D01*
X67303Y51208D01*
X67903Y51075D01*
Y53875D01*
G01X67103Y55608D02*
X67570Y56008D01*
X67836Y56542D01*
X67903Y57142D01*
X67836Y57675D01*
X67503Y58208D01*
X67103Y58542D01*
X66703Y58608D01*
X66236Y58475D01*
X65903Y58008D01*
X65770Y57542D01*
Y56942D01*
G01Y57542D02*
X65570Y57942D01*
X65236Y58275D01*
X64836Y58408D01*
X64436Y58275D01*
X64103Y57942D01*
X63903Y57342D01*
X63970Y56742D01*
X64236Y56142D01*
G01X196851Y-7874D02*
G03Y0I0J3937D01*
G01X189564Y-19685D02*
G03X181690I-3937J0D01*
G01X165355Y0D02*
G03Y-7874I0J-3937D01*
G01X140158D02*
G03Y0I0J3937D01*
G01X185040Y18307D02*
G03X177166I-3937J0D01*
G01X189564Y-19685D02*
X539370D01*
G01X165355Y-7874D02*
X196851D01*
G01X211024Y19685D02*
G03X194489I-8267J0D01*
G01D02*
G03X211024I8267J0D01*
G01D02*
G03X194489I-8267J0D01*
G01D02*
G03X211024I8267J0D01*
G01D02*
G03X194489I-8267J0D01*
G01D02*
G03X211024I8267J0D01*
G01D02*
G03X194489I-8267J0D01*
G01D02*
G03X211024I8267J0D01*
G01X194489D02*
G03X211024I8267J0D01*
G01D02*
G03X194489I-8267J0D01*
G01D02*
G03X211024I8267J0D01*
G01D02*
G03X194489I-8267J0D01*
G01X188977Y0D02*
X358268D01*
G01X185040Y3937D02*
G03X188977Y0I3937J0D01*
G01X185040Y57874D02*
Y3937D01*
G01X167717Y19685D02*
G03X151181I-8268J0D01*
G01D02*
G03X167717I8268J0D01*
G01D02*
G03X151181I-8268J0D01*
G01D02*
G03X167717I8268J0D01*
G01D02*
G03X151181I-8268J0D01*
G01D02*
G03X167717I8268J0D01*
G01D02*
G03X151181I-8268J0D01*
G01D02*
G03X167717I8268J0D01*
G01X151181D02*
G03X167717I8268J0D01*
G01D02*
G03X151181I-8268J0D01*
G01D02*
G03X167717I8268J0D01*
G01D02*
G03X151181I-8268J0D01*
G01X177166Y3937D02*
Y57874D01*
G01X173229Y0D02*
G03X177166Y3937I0J3937D01*
G01X185040Y87992D02*
G03X177166I-3937J0D01*
G01Y113189D02*
G03X185040I3937J0D01*
G01X196851Y61811D02*
G03Y69685I0J3937D01*
G01X165355D02*
G03Y61811I0J-3937D01*
G01X140158D02*
G03Y69685I0J3937D01*
G01X177166Y43504D02*
G03X185040I3937J0D01*
G01X167717Y89370D02*
G03X151181I-8268J0D01*
G01D02*
G03X167717I8268J0D01*
G01D02*
G03X151181I-8268J0D01*
G01D02*
G03X167717I8268J0D01*
G01D02*
G03X151181I-8268J0D01*
G01D02*
G03X167717I8268J0D01*
G01D02*
G03X151181I-8268J0D01*
G01D02*
G03X167717I8268J0D01*
G01X151181D02*
G03X167717I8268J0D01*
G01D02*
G03X151181I-8268J0D01*
G01D02*
G03X167717I8268J0D01*
G01D02*
G03X151181I-8268J0D01*
G01X177166Y73622D02*
Y127559D01*
G01X173229Y69685D02*
G03X177166Y73622I0J3937D01*
G01X211024Y89370D02*
G03X194489I-8267J0D01*
G01D02*
G03X211024I8267J0D01*
G01D02*
G03X194489I-8267J0D01*
G01D02*
G03X211024I8267J0D01*
G01D02*
G03X194489I-8267J0D01*
G01D02*
G03X211024I8267J0D01*
G01D02*
G03X194489I-8267J0D01*
G01D02*
G03X211024I8267J0D01*
G01X194489D02*
G03X211024I8267J0D01*
G01D02*
G03X194489I-8267J0D01*
G01D02*
G03X211024I8267J0D01*
G01D02*
G03X194489I-8267J0D01*
G01X188977Y69685D02*
X358268D01*
G01X185040Y73622D02*
G03X188977Y69685I3937J0D01*
G01X185040Y127559D02*
Y73622D01*
G01X188977Y61811D02*
G03X185040Y57874I0J-3937D01*
G01X358268Y61811D02*
X188977D01*
G01X177166Y57874D02*
G03X173229Y61811I-3937J0D01*
G01X185040Y157677D02*
G03X177166I-3937J0D01*
G01Y182874D02*
G03X185040I3937J0D01*
G01X196851Y131496D02*
G03Y139370I0J3937D01*
G01X165355D02*
G03Y131496I0J-3937D01*
G01X140158D02*
G03Y139370I0J3937D01*
G01X167717Y159055D02*
G03X151181I-8268J0D01*
G01D02*
G03X167717I8268J0D01*
G01D02*
G03X151181I-8268J0D01*
G01D02*
G03X167717I8268J0D01*
G01D02*
G03X151181I-8268J0D01*
G01D02*
G03X167717I8268J0D01*
G01D02*
G03X151181I-8268J0D01*
G01D02*
G03X167717I8268J0D01*
G01X151181D02*
G03X167717I8268J0D01*
G01D02*
G03X151181I-8268J0D01*
G01D02*
G03X167717I8268J0D01*
G01D02*
G03X151181I-8268J0D01*
G01X177166Y143307D02*
Y197244D01*
G01X173229Y139370D02*
G03X177166Y143307I0J3937D01*
G01Y127559D02*
G03X173229Y131496I-3937J0D01*
G01X211024Y159055D02*
G03X194489I-8267J0D01*
G01D02*
G03X211024I8267J0D01*
G01D02*
G03X194489I-8267J0D01*
G01D02*
G03X211024I8267J0D01*
G01D02*
G03X194489I-8267J0D01*
G01D02*
G03X211024I8267J0D01*
G01D02*
G03X194489I-8267J0D01*
G01D02*
G03X211024I8267J0D01*
G01X194489D02*
G03X211024I8267J0D01*
G01D02*
G03X194489I-8267J0D01*
G01D02*
G03X211024I8267J0D01*
G01D02*
G03X194489I-8267J0D01*
G01X188977Y139370D02*
X358268D01*
G01X185040Y143307D02*
G03X188977Y139370I3937J0D01*
G01X185040Y197244D02*
Y143307D01*
G01X188977Y131496D02*
G03X185040Y127559I0J-3937D01*
G01X358268Y131496D02*
X188977D01*
G01X185040Y227362D02*
G03X177166I-3937J0D01*
G01Y252559D02*
G03X185040I3937J0D01*
G01X196851Y270866D02*
G03Y278740I0J3937D01*
G01X165355D02*
G03Y270866I0J-3937D01*
G01X140158D02*
G03Y278740I0J3937D01*
G01X196851Y201181D02*
G03Y209055I0J3937D01*
G01X165355D02*
G03Y201181I0J-3937D01*
G01X140158D02*
G03Y209055I0J3937D01*
G01X173229Y278740D02*
G03X177166Y282677I0J3937D01*
G01X188977Y278740D02*
X358268D01*
G01X185040Y282677D02*
G03X188977Y278740I3937J0D01*
G01X167717Y228740D02*
G03X151181I-8268J0D01*
G01D02*
G03X167717I8268J0D01*
G01D02*
G03X151181I-8268J0D01*
G01D02*
G03X167717I8268J0D01*
G01D02*
G03X151181I-8268J0D01*
G01D02*
G03X167717I8268J0D01*
G01D02*
G03X151181I-8268J0D01*
G01D02*
G03X167717I8268J0D01*
G01X151181D02*
G03X167717I8268J0D01*
G01D02*
G03X151181I-8268J0D01*
G01D02*
G03X167717I8268J0D01*
G01D02*
G03X151181I-8268J0D01*
G01X177166Y212992D02*
Y266929D01*
G01X173229Y209055D02*
G03X177166Y212992I0J3937D01*
G01Y266929D02*
G03X173229Y270866I-3937J0D01*
G01X211024Y228740D02*
G03X194489I-8267J0D01*
G01D02*
G03X211024I8267J0D01*
G01D02*
G03X194489I-8267J0D01*
G01D02*
G03X211024I8267J0D01*
G01D02*
G03X194489I-8267J0D01*
G01D02*
G03X211024I8267J0D01*
G01D02*
G03X194489I-8267J0D01*
G01D02*
G03X211024I8267J0D01*
G01X194489D02*
G03X211024I8267J0D01*
G01D02*
G03X194489I-8267J0D01*
G01D02*
G03X211024I8267J0D01*
G01D02*
G03X194489I-8267J0D01*
G01X188977Y209055D02*
X358268D01*
G01X185040Y212992D02*
G03X188977Y209055I3937J0D01*
G01X185040Y266929D02*
Y212992D01*
G01X188977Y270866D02*
G03X185040Y266929I0J-3937D01*
G01X358268Y270866D02*
X188977D01*
G01X177166Y197244D02*
G03X173229Y201181I-3937J0D01*
G01X188977D02*
G03X185040Y197244I0J-3937D01*
G01X358268Y201181D02*
X188977D01*
G01X185040Y297047D02*
G03X177166I-3937J0D01*
G01Y322244D02*
G03X185040I3937J0D01*
G01X196851Y340551D02*
G03Y348425I0J3937D01*
G01X165355D02*
G03Y340551I0J-3937D01*
G01X140158D02*
G03Y348425I0J3937D01*
G01X151181Y368110D02*
G03X167717I8268J0D01*
G01X151181D02*
G03X167717I8268J0D01*
G01X151181D02*
G03X167717I8268J0D01*
G01X151181D02*
G03X167717I8268J0D01*
G01X151181D02*
G03X167717I8268J0D01*
G01X151181D02*
G03X167717I8268J0D01*
G01X177166Y352362D02*
Y406299D01*
G01X173229Y348425D02*
G03X177166Y352362I0J3937D01*
G01X194489Y368110D02*
G03X211024I8267J0D01*
G01X194489D02*
G03X211024I8267J0D01*
G01X194489D02*
G03X211024I8267J0D01*
G01X194489D02*
G03X211024I8267J0D01*
G01X194489D02*
G03X211024I8267J0D01*
G01X194489D02*
G03X211024I8267J0D01*
G01X188977Y348425D02*
X358268D01*
G01X185040Y352362D02*
G03X188977Y348425I3937J0D01*
G01X185040Y406299D02*
Y352362D01*
G01X167717Y298425D02*
G03X151181I-8268J0D01*
G01D02*
G03X167717I8268J0D01*
G01D02*
G03X151181I-8268J0D01*
G01D02*
G03X167717I8268J0D01*
G01D02*
G03X151181I-8268J0D01*
G01D02*
G03X167717I8268J0D01*
G01D02*
G03X151181I-8268J0D01*
G01D02*
G03X167717I8268J0D01*
G01X151181D02*
G03X167717I8268J0D01*
G01D02*
G03X151181I-8268J0D01*
G01D02*
G03X167717I8268J0D01*
G01D02*
G03X151181I-8268J0D01*
G01X177166Y282677D02*
Y336614D01*
G01D02*
G03X173229Y340551I-3937J0D01*
G01X211024Y298425D02*
G03X194489I-8267J0D01*
G01D02*
G03X211024I8267J0D01*
G01D02*
G03X194489I-8267J0D01*
G01D02*
G03X211024I8267J0D01*
G01D02*
G03X194489I-8267J0D01*
G01D02*
G03X211024I8267J0D01*
G01D02*
G03X194489I-8267J0D01*
G01D02*
G03X211024I8267J0D01*
G01X194489D02*
G03X211024I8267J0D01*
G01D02*
G03X194489I-8267J0D01*
G01D02*
G03X211024I8267J0D01*
G01D02*
G03X194489I-8267J0D01*
G01X185040Y336614D02*
Y282677D01*
G01X188977Y340551D02*
G03X185040Y336614I0J-3937D01*
G01X358268Y340551D02*
X188977D01*
G01X185040Y436417D02*
G03X177166I-3937J0D01*
G01X185040Y366732D02*
G03X177166I-3937J0D01*
G01Y391929D02*
G03X185040I3937J0D01*
G01X196851Y410236D02*
G03Y418110I0J3937D01*
G01X165355D02*
G03Y410236I0J-3937D01*
G01X140158D02*
G03Y418110I0J3937D01*
G01X167717Y437795D02*
G03X151181I-8268J0D01*
G01D02*
G03X167717I8268J0D01*
G01D02*
G03X151181I-8268J0D01*
G01D02*
G03X167717I8268J0D01*
G01D02*
G03X151181I-8268J0D01*
G01D02*
G03X167717I8268J0D01*
G01D02*
G03X151181I-8268J0D01*
G01D02*
G03X167717I8268J0D01*
G01X151181D02*
G03X167717I8268J0D01*
G01D02*
G03X151181I-8268J0D01*
G01D02*
G03X167717I8268J0D01*
G01D02*
G03X151181I-8268J0D01*
G01X177166Y422047D02*
Y475984D01*
G01X173229Y418110D02*
G03X177166Y422047I0J3937D01*
G01X211024Y437795D02*
G03X194489I-8267J0D01*
G01D02*
G03X211024I8267J0D01*
G01D02*
G03X194489I-8267J0D01*
G01D02*
G03X211024I8267J0D01*
G01D02*
G03X194489I-8267J0D01*
G01D02*
G03X211024I8267J0D01*
G01D02*
G03X194489I-8267J0D01*
G01D02*
G03X211024I8267J0D01*
G01X194489D02*
G03X211024I8267J0D01*
G01D02*
G03X194489I-8267J0D01*
G01D02*
G03X211024I8267J0D01*
G01D02*
G03X194489I-8267J0D01*
G01X188977Y418110D02*
X358268D01*
G01X185040Y422047D02*
G03X188977Y418110I3937J0D01*
G01X185040Y475984D02*
Y422047D01*
G01X167717Y368110D02*
G03X151181I-8268J0D01*
G01X167717D02*
G03X151181I-8268J0D01*
G01X167717D02*
G03X151181I-8268J0D01*
G01X167717D02*
G03X151181I-8268J0D01*
G01X167717D02*
G03X151181I-8268J0D01*
G01X167717D02*
G03X151181I-8268J0D01*
G01X177166Y406299D02*
G03X173229Y410236I-3937J0D01*
G01X211024Y368110D02*
G03X194489I-8267J0D01*
G01X211024D02*
G03X194489I-8267J0D01*
G01X211024D02*
G03X194489I-8267J0D01*
G01X211024D02*
G03X194489I-8267J0D01*
G01X211024D02*
G03X194489I-8267J0D01*
G01X211024D02*
G03X194489I-8267J0D01*
G01X188977Y410236D02*
G03X185040Y406299I0J-3937D01*
G01X358268Y410236D02*
X188977D01*
G01X185040Y506102D02*
G03X177166I-3937J0D01*
G01Y531299D02*
G03X185040I3937J0D01*
G01X177166Y461614D02*
G03X185040I3937J0D01*
G01X196851Y479921D02*
G03Y487795I0J3937D01*
G01X165355D02*
G03Y479921I0J-3937D01*
G01X140158D02*
G03Y487795I0J3937D01*
G01X167717Y507480D02*
G03X151181I-8268J0D01*
G01D02*
G03X167717I8268J0D01*
G01D02*
G03X151181I-8268J0D01*
G01D02*
G03X167717I8268J0D01*
G01D02*
G03X151181I-8268J0D01*
G01D02*
G03X167717I8268J0D01*
G01D02*
G03X151181I-8268J0D01*
G01D02*
G03X167717I8268J0D01*
G01X151181D02*
G03X167717I8268J0D01*
G01D02*
G03X151181I-8268J0D01*
G01D02*
G03X167717I8268J0D01*
G01D02*
G03X151181I-8268J0D01*
G01X177166Y491732D02*
Y545669D01*
G01X173229Y487795D02*
G03X177166Y491732I0J3937D01*
G01X211024Y507480D02*
G03X194489I-8267J0D01*
G01D02*
G03X211024I8267J0D01*
G01D02*
G03X194489I-8267J0D01*
G01D02*
G03X211024I8267J0D01*
G01D02*
G03X194489I-8267J0D01*
G01D02*
G03X211024I8267J0D01*
G01D02*
G03X194489I-8267J0D01*
G01D02*
G03X211024I8267J0D01*
G01X194489D02*
G03X211024I8267J0D01*
G01D02*
G03X194489I-8267J0D01*
G01D02*
G03X211024I8267J0D01*
G01D02*
G03X194489I-8267J0D01*
G01X188977Y487795D02*
X358268D01*
G01X185040Y491732D02*
G03X188977Y487795I3937J0D01*
G01X185040Y545669D02*
Y491732D01*
G01X177166Y475984D02*
G03X173229Y479921I-3937J0D01*
G01X188977D02*
G03X185040Y475984I0J-3937D01*
G01X358268Y479921D02*
X188977D01*
G01X185040Y575787D02*
G03X177166I-3937J0D01*
G01Y600984D02*
G03X185040I3937J0D01*
G01X196851Y549606D02*
G03Y557480I0J3937D01*
G01X165355D02*
G03Y549606I0J-3937D01*
G01X140158D02*
G03Y557480I0J3937D01*
G01X167717Y577165D02*
G03X151181I-8268J0D01*
G01D02*
G03X167717I8268J0D01*
G01D02*
G03X151181I-8268J0D01*
G01D02*
G03X167717I8268J0D01*
G01D02*
G03X151181I-8268J0D01*
G01D02*
G03X167717I8268J0D01*
G01D02*
G03X151181I-8268J0D01*
G01D02*
G03X167717I8268J0D01*
G01X151181D02*
G03X167717I8268J0D01*
G01D02*
G03X151181I-8268J0D01*
G01D02*
G03X167717I8268J0D01*
G01D02*
G03X151181I-8268J0D01*
G01X177166Y561417D02*
Y615354D01*
G01X173229Y557480D02*
G03X177166Y561417I0J3937D01*
G01X211024Y577165D02*
G03X194489I-8267J0D01*
G01D02*
G03X211024I8267J0D01*
G01D02*
G03X194489I-8267J0D01*
G01D02*
G03X211024I8267J0D01*
G01D02*
G03X194489I-8267J0D01*
G01D02*
G03X211024I8267J0D01*
G01D02*
G03X194489I-8267J0D01*
G01D02*
G03X211024I8267J0D01*
G01X194489D02*
G03X211024I8267J0D01*
G01D02*
G03X194489I-8267J0D01*
G01D02*
G03X211024I8267J0D01*
G01D02*
G03X194489I-8267J0D01*
G01X188977Y557480D02*
X358268D01*
G01X185040Y561417D02*
G03X188977Y557480I3937J0D01*
G01X185040Y615354D02*
Y561417D01*
G01X177166Y545669D02*
G03X173229Y549606I-3937J0D01*
G01X188977D02*
G03X185040Y545669I0J-3937D01*
G01X358268Y549606D02*
X188977D01*
G01X185040Y645472D02*
G03X177166I-3937J0D01*
G01Y670669D02*
G03X185040I3937J0D01*
G01X196851Y619291D02*
G03Y627165I0J3937D01*
G01X165355D02*
G03Y619291I0J-3937D01*
G01X140158D02*
G03Y627165I0J3937D01*
G01X167717Y646850D02*
G03X151181I-8268J0D01*
G01D02*
G03X167717I8268J0D01*
G01D02*
G03X151181I-8268J0D01*
G01D02*
G03X167717I8268J0D01*
G01D02*
G03X151181I-8268J0D01*
G01D02*
G03X167717I8268J0D01*
G01D02*
G03X151181I-8268J0D01*
G01D02*
G03X167717I8268J0D01*
G01X151181D02*
G03X167717I8268J0D01*
G01D02*
G03X151181I-8268J0D01*
G01D02*
G03X167717I8268J0D01*
G01D02*
G03X151181I-8268J0D01*
G01X177166Y631102D02*
Y685039D01*
G01X173229Y627165D02*
G03X177166Y631102I0J3937D01*
G01Y685039D02*
G03X173229Y688976I-3937J0D01*
G01X211024Y646850D02*
G03X194489I-8267J0D01*
G01D02*
G03X211024I8267J0D01*
G01D02*
G03X194489I-8267J0D01*
G01D02*
G03X211024I8267J0D01*
G01D02*
G03X194489I-8267J0D01*
G01D02*
G03X211024I8267J0D01*
G01D02*
G03X194489I-8267J0D01*
G01D02*
G03X211024I8267J0D01*
G01X194489D02*
G03X211024I8267J0D01*
G01D02*
G03X194489I-8267J0D01*
G01D02*
G03X211024I8267J0D01*
G01D02*
G03X194489I-8267J0D01*
G01X188977Y627165D02*
X358268D01*
G01X185040Y631102D02*
G03X188977Y627165I3937J0D01*
G01X185040Y685039D02*
Y631102D01*
G01X188977Y688976D02*
G03X185040Y685039I0J-3937D01*
G01X358268Y688976D02*
X188977D01*
G01X177166Y615354D02*
G03X173229Y619291I-3937J0D01*
G01X188977D02*
G03X185040Y615354I0J-3937D01*
G01X358268Y619291D02*
X188977D01*
G01X222048Y0D02*
G03Y-7874I0J-3937D01*
G01D02*
X325197D01*
G01X222048Y69685D02*
G03Y61811I0J-3937D01*
G01Y139370D02*
G03Y131496I0J-3937D01*
G01Y278740D02*
G03Y270866I0J-3937D01*
G01Y209055D02*
G03Y201181I0J-3937D01*
G01Y348425D02*
G03Y340551I0J-3937D01*
G01Y418110D02*
G03Y410236I0J-3937D01*
G01Y487795D02*
G03Y479921I0J-3937D01*
G01Y557480D02*
G03Y549606I0J-3937D01*
G01Y627165D02*
G03Y619291I0J-3937D01*
G01X370079Y18307D02*
G03X362205I-3937J0D01*
G01X350394Y0D02*
G03Y-7874I0J-3937D01*
G01X325197D02*
G03Y0I0J3937D01*
G01X350394Y-7874D02*
X381890D01*
G01X352756Y19685D02*
G03X336221I-8267J0D01*
G01D02*
G03X352756I8268J0D01*
G01D02*
G03X336221I-8267J0D01*
G01D02*
G03X352756I8268J0D01*
G01D02*
G03X336221I-8267J0D01*
G01D02*
G03X352756I8268J0D01*
G01D02*
G03X336221I-8267J0D01*
G01D02*
G03X352756I8268J0D01*
G01X336221D02*
G03X352756I8268J0D01*
G01D02*
G03X336221I-8267J0D01*
G01D02*
G03X352756I8268J0D01*
G01D02*
G03X336221I-8267J0D01*
G01X362205Y3937D02*
Y57874D01*
G01X358268Y0D02*
G03X362205Y3937I0J3937D01*
G01X370079Y87992D02*
G03X362205I-3937J0D01*
G01Y113189D02*
G03X370079I3937J0D01*
G01X362205Y43504D02*
G03X370079I3937J0D01*
G01X350394Y69685D02*
G03Y61811I0J-3937D01*
G01X325197D02*
G03Y69685I0J3937D01*
G01X352756Y89370D02*
G03X336221I-8267J0D01*
G01D02*
G03X352756I8268J0D01*
G01D02*
G03X336221I-8267J0D01*
G01D02*
G03X352756I8268J0D01*
G01D02*
G03X336221I-8267J0D01*
G01D02*
G03X352756I8268J0D01*
G01D02*
G03X336221I-8267J0D01*
G01D02*
G03X352756I8268J0D01*
G01X336221D02*
G03X352756I8268J0D01*
G01D02*
G03X336221I-8267J0D01*
G01D02*
G03X352756I8268J0D01*
G01D02*
G03X336221I-8267J0D01*
G01X362205Y73622D02*
Y127559D01*
G01X358268Y69685D02*
G03X362205Y73622I0J3937D01*
G01Y57874D02*
G03X358268Y61811I-3937J0D01*
G01X370079Y157677D02*
G03X362205I-3937J0D01*
G01Y182874D02*
G03X370079I3937J0D01*
G01X350394Y139370D02*
G03Y131496I0J-3937D01*
G01X325197D02*
G03Y139370I0J3937D01*
G01X352756Y159055D02*
G03X336221I-8267J0D01*
G01D02*
G03X352756I8268J0D01*
G01D02*
G03X336221I-8267J0D01*
G01D02*
G03X352756I8268J0D01*
G01D02*
G03X336221I-8267J0D01*
G01D02*
G03X352756I8268J0D01*
G01D02*
G03X336221I-8267J0D01*
G01D02*
G03X352756I8268J0D01*
G01X336221D02*
G03X352756I8268J0D01*
G01D02*
G03X336221I-8267J0D01*
G01D02*
G03X352756I8268J0D01*
G01D02*
G03X336221I-8267J0D01*
G01X362205Y143307D02*
Y197244D01*
G01X358268Y139370D02*
G03X362205Y143307I0J3937D01*
G01Y127559D02*
G03X358268Y131496I-3937J0D01*
G01X370079Y227362D02*
G03X362205I-3937J0D01*
G01Y252559D02*
G03X370079I3937J0D01*
G01X350394Y278740D02*
G03Y270866I0J-3937D01*
G01X325197D02*
G03Y278740I0J3937D01*
G01X350394Y209055D02*
G03Y201181I0J-3937D01*
G01X325197D02*
G03Y209055I0J3937D01*
G01X358268Y278740D02*
G03X362205Y282677I0J3937D01*
G01X352756Y228740D02*
G03X336221I-8267J0D01*
G01D02*
G03X352756I8268J0D01*
G01D02*
G03X336221I-8267J0D01*
G01D02*
G03X352756I8268J0D01*
G01D02*
G03X336221I-8267J0D01*
G01D02*
G03X352756I8268J0D01*
G01D02*
G03X336221I-8267J0D01*
G01D02*
G03X352756I8268J0D01*
G01X336221D02*
G03X352756I8268J0D01*
G01D02*
G03X336221I-8267J0D01*
G01D02*
G03X352756I8268J0D01*
G01D02*
G03X336221I-8267J0D01*
G01X362205Y212992D02*
Y266929D01*
G01X358268Y209055D02*
G03X362205Y212992I0J3937D01*
G01Y266929D02*
G03X358268Y270866I-3937J0D01*
G01X362205Y197244D02*
G03X358268Y201181I-3937J0D01*
G01X370079Y297047D02*
G03X362205I-3937J0D01*
G01Y322244D02*
G03X370079I3937J0D01*
G01X350394Y348425D02*
G03Y340551I0J-3937D01*
G01X325197D02*
G03Y348425I0J3937D01*
G01X336221Y368110D02*
G03X352756I8268J0D01*
G01X336221D02*
G03X352756I8268J0D01*
G01X336221D02*
G03X352756I8268J0D01*
G01X336221D02*
G03X352756I8268J0D01*
G01X336221D02*
G03X352756I8268J0D01*
G01X336221D02*
G03X352756I8268J0D01*
G01X362205Y352362D02*
Y406299D01*
G01X358268Y348425D02*
G03X362205Y352362I0J3937D01*
G01X352756Y298425D02*
G03X336221I-8267J0D01*
G01D02*
G03X352756I8268J0D01*
G01D02*
G03X336221I-8267J0D01*
G01D02*
G03X352756I8268J0D01*
G01D02*
G03X336221I-8267J0D01*
G01D02*
G03X352756I8268J0D01*
G01D02*
G03X336221I-8267J0D01*
G01D02*
G03X352756I8268J0D01*
G01X336221D02*
G03X352756I8268J0D01*
G01D02*
G03X336221I-8267J0D01*
G01D02*
G03X352756I8268J0D01*
G01D02*
G03X336221I-8267J0D01*
G01X362205Y282677D02*
Y336614D01*
G01D02*
G03X358268Y340551I-3937J0D01*
G01X370079Y436417D02*
G03X362205I-3937J0D01*
G01X370079Y366732D02*
G03X362205I-3937J0D01*
G01Y391929D02*
G03X370079I3937J0D01*
G01X350394Y418110D02*
G03Y410236I0J-3937D01*
G01X325197D02*
G03Y418110I0J3937D01*
G01X352756Y437795D02*
G03X336221I-8267J0D01*
G01D02*
G03X352756I8268J0D01*
G01D02*
G03X336221I-8267J0D01*
G01D02*
G03X352756I8268J0D01*
G01D02*
G03X336221I-8267J0D01*
G01D02*
G03X352756I8268J0D01*
G01D02*
G03X336221I-8267J0D01*
G01D02*
G03X352756I8268J0D01*
G01X336221D02*
G03X352756I8268J0D01*
G01D02*
G03X336221I-8267J0D01*
G01D02*
G03X352756I8268J0D01*
G01D02*
G03X336221I-8267J0D01*
G01X362205Y422047D02*
Y475984D01*
G01X358268Y418110D02*
G03X362205Y422047I0J3937D01*
G01X352756Y368110D02*
G03X336221I-8267J0D01*
G01X352756D02*
G03X336221I-8267J0D01*
G01X352756D02*
G03X336221I-8267J0D01*
G01X352756D02*
G03X336221I-8267J0D01*
G01X352756D02*
G03X336221I-8267J0D01*
G01X352756D02*
G03X336221I-8267J0D01*
G01X362205Y406299D02*
G03X358268Y410236I-3937J0D01*
G01X370079Y506102D02*
G03X362205I-3937J0D01*
G01Y531299D02*
G03X370079I3937J0D01*
G01X362205Y461614D02*
G03X370079I3937J0D01*
G01X350394Y487795D02*
G03Y479921I0J-3937D01*
G01X325197D02*
G03Y487795I0J3937D01*
G01X352756Y507480D02*
G03X336221I-8267J0D01*
G01D02*
G03X352756I8268J0D01*
G01D02*
G03X336221I-8267J0D01*
G01D02*
G03X352756I8268J0D01*
G01D02*
G03X336221I-8267J0D01*
G01D02*
G03X352756I8268J0D01*
G01D02*
G03X336221I-8267J0D01*
G01D02*
G03X352756I8268J0D01*
G01X336221D02*
G03X352756I8268J0D01*
G01D02*
G03X336221I-8267J0D01*
G01D02*
G03X352756I8268J0D01*
G01D02*
G03X336221I-8267J0D01*
G01X362205Y491732D02*
Y545669D01*
G01X358268Y487795D02*
G03X362205Y491732I0J3937D01*
G01Y475984D02*
G03X358268Y479921I-3937J0D01*
G01X370079Y575787D02*
G03X362205I-3937J0D01*
G01Y600984D02*
G03X370079I3937J0D01*
G01X350394Y557480D02*
G03Y549606I0J-3937D01*
G01X325197D02*
G03Y557480I0J3937D01*
G01X352756Y577165D02*
G03X336221I-8267J0D01*
G01D02*
G03X352756I8268J0D01*
G01D02*
G03X336221I-8267J0D01*
G01D02*
G03X352756I8268J0D01*
G01D02*
G03X336221I-8267J0D01*
G01D02*
G03X352756I8268J0D01*
G01D02*
G03X336221I-8267J0D01*
G01D02*
G03X352756I8268J0D01*
G01X336221D02*
G03X352756I8268J0D01*
G01D02*
G03X336221I-8267J0D01*
G01D02*
G03X352756I8268J0D01*
G01D02*
G03X336221I-8267J0D01*
G01X362205Y561417D02*
Y615354D01*
G01X358268Y557480D02*
G03X362205Y561417I0J3937D01*
G01Y545669D02*
G03X358268Y549606I-3937J0D01*
G01X370079Y645472D02*
G03X362205I-3937J0D01*
G01Y670669D02*
G03X370079I3937J0D01*
G01X350394Y627165D02*
G03Y619291I0J-3937D01*
G01X325197D02*
G03Y627165I0J3937D01*
G01X352756Y646850D02*
G03X336221I-8267J0D01*
G01D02*
G03X352756I8268J0D01*
G01D02*
G03X336221I-8267J0D01*
G01D02*
G03X352756I8268J0D01*
G01D02*
G03X336221I-8267J0D01*
G01D02*
G03X352756I8268J0D01*
G01D02*
G03X336221I-8267J0D01*
G01D02*
G03X352756I8268J0D01*
G01X336221D02*
G03X352756I8268J0D01*
G01D02*
G03X336221I-8267J0D01*
G01D02*
G03X352756I8268J0D01*
G01D02*
G03X336221I-8267J0D01*
G01X362205Y631102D02*
Y685039D01*
G01X358268Y627165D02*
G03X362205Y631102I0J3937D01*
G01Y685039D02*
G03X358268Y688976I-3937J0D01*
G01X362205Y615354D02*
G03X358268Y619291I-3937J0D01*
G01X407087Y0D02*
G03Y-7874I0J-3937D01*
G01X381890D02*
G03Y0I0J3937D01*
G01X407087Y-7874D02*
X510237D01*
G01X396063Y19685D02*
G03X379528I-8268J0D01*
G01D02*
G03X396063I8267J0D01*
G01D02*
G03X379528I-8268J0D01*
G01D02*
G03X396063I8267J0D01*
G01D02*
G03X379528I-8268J0D01*
G01D02*
G03X396063I8267J0D01*
G01D02*
G03X379528I-8268J0D01*
G01D02*
G03X396063I8267J0D01*
G01X379528D02*
G03X396063I8267J0D01*
G01D02*
G03X379528I-8268J0D01*
G01D02*
G03X396063I8267J0D01*
G01D02*
G03X379528I-8268J0D01*
G01X374016Y0D02*
X543307D01*
G01X370079Y3937D02*
G03X374016Y0I3937J0D01*
G01X370079Y57874D02*
Y3937D01*
G01X407087Y69685D02*
G03Y61811I0J-3937D01*
G01X381890D02*
G03Y69685I0J3937D01*
G01X396063Y89370D02*
G03X379528I-8268J0D01*
G01D02*
G03X396063I8267J0D01*
G01D02*
G03X379528I-8268J0D01*
G01D02*
G03X396063I8267J0D01*
G01D02*
G03X379528I-8268J0D01*
G01D02*
G03X396063I8267J0D01*
G01D02*
G03X379528I-8268J0D01*
G01D02*
G03X396063I8267J0D01*
G01X379528D02*
G03X396063I8267J0D01*
G01D02*
G03X379528I-8268J0D01*
G01D02*
G03X396063I8267J0D01*
G01D02*
G03X379528I-8268J0D01*
G01X374016Y69685D02*
X543307D01*
G01X370079Y73622D02*
G03X374016Y69685I3937J0D01*
G01X370079Y127559D02*
Y73622D01*
G01X374016Y61811D02*
G03X370079Y57874I0J-3937D01*
G01X543307Y61811D02*
X374016D01*
G01X407087Y139370D02*
G03Y131496I0J-3937D01*
G01X381890D02*
G03Y139370I0J3937D01*
G01X396063Y159055D02*
G03X379528I-8268J0D01*
G01D02*
G03X396063I8267J0D01*
G01D02*
G03X379528I-8268J0D01*
G01D02*
G03X396063I8267J0D01*
G01D02*
G03X379528I-8268J0D01*
G01D02*
G03X396063I8267J0D01*
G01D02*
G03X379528I-8268J0D01*
G01D02*
G03X396063I8267J0D01*
G01X379528D02*
G03X396063I8267J0D01*
G01D02*
G03X379528I-8268J0D01*
G01D02*
G03X396063I8267J0D01*
G01D02*
G03X379528I-8268J0D01*
G01X374016Y139370D02*
X543307D01*
G01X370079Y143307D02*
G03X374016Y139370I3937J0D01*
G01X370079Y197244D02*
Y143307D01*
G01X374016Y131496D02*
G03X370079Y127559I0J-3937D01*
G01X543307Y131496D02*
X374016D01*
G01X407087Y278740D02*
G03Y270866I0J-3937D01*
G01X381890D02*
G03Y278740I0J3937D01*
G01X407087Y209055D02*
G03Y201181I0J-3937D01*
G01X381890D02*
G03Y209055I0J3937D01*
G01X374016Y278740D02*
X543307D01*
G01X370079Y282677D02*
G03X374016Y278740I3937J0D01*
G01X396063Y228740D02*
G03X379528I-8268J0D01*
G01D02*
G03X396063I8267J0D01*
G01D02*
G03X379528I-8268J0D01*
G01D02*
G03X396063I8267J0D01*
G01D02*
G03X379528I-8268J0D01*
G01D02*
G03X396063I8267J0D01*
G01D02*
G03X379528I-8268J0D01*
G01D02*
G03X396063I8267J0D01*
G01X379528D02*
G03X396063I8267J0D01*
G01D02*
G03X379528I-8268J0D01*
G01D02*
G03X396063I8267J0D01*
G01D02*
G03X379528I-8268J0D01*
G01X374016Y209055D02*
X543307D01*
G01X370079Y212992D02*
G03X374016Y209055I3937J0D01*
G01X370079Y266929D02*
Y212992D01*
G01X374016Y270866D02*
G03X370079Y266929I0J-3937D01*
G01X543307Y270866D02*
X374016D01*
G01Y201181D02*
G03X370079Y197244I0J-3937D01*
G01X543307Y201181D02*
X374016D01*
G01X407087Y348425D02*
G03Y340551I0J-3937D01*
G01X381890D02*
G03Y348425I0J3937D01*
G01X379528Y368110D02*
G03X396063I8267J0D01*
G01X379528D02*
G03X396063I8267J0D01*
G01X379528D02*
G03X396063I8267J0D01*
G01X379528D02*
G03X396063I8267J0D01*
G01X379528D02*
G03X396063I8267J0D01*
G01X379528D02*
G03X396063I8267J0D01*
G01X374016Y348425D02*
X543307D01*
G01X370079Y352362D02*
G03X374016Y348425I3937J0D01*
G01X370079Y406299D02*
Y352362D01*
G01X396063Y298425D02*
G03X379528I-8268J0D01*
G01D02*
G03X396063I8267J0D01*
G01D02*
G03X379528I-8268J0D01*
G01D02*
G03X396063I8267J0D01*
G01D02*
G03X379528I-8268J0D01*
G01D02*
G03X396063I8267J0D01*
G01D02*
G03X379528I-8268J0D01*
G01D02*
G03X396063I8267J0D01*
G01X379528D02*
G03X396063I8267J0D01*
G01D02*
G03X379528I-8268J0D01*
G01D02*
G03X396063I8267J0D01*
G01D02*
G03X379528I-8268J0D01*
G01X370079Y336614D02*
Y282677D01*
G01X374016Y340551D02*
G03X370079Y336614I0J-3937D01*
G01X543307Y340551D02*
X374016D01*
G01X407087Y418110D02*
G03Y410236I0J-3937D01*
G01X381890D02*
G03Y418110I0J3937D01*
G01X396063Y437795D02*
G03X379528I-8268J0D01*
G01D02*
G03X396063I8267J0D01*
G01D02*
G03X379528I-8268J0D01*
G01D02*
G03X396063I8267J0D01*
G01D02*
G03X379528I-8268J0D01*
G01D02*
G03X396063I8267J0D01*
G01D02*
G03X379528I-8268J0D01*
G01D02*
G03X396063I8267J0D01*
G01X379528D02*
G03X396063I8267J0D01*
G01D02*
G03X379528I-8268J0D01*
G01D02*
G03X396063I8267J0D01*
G01D02*
G03X379528I-8268J0D01*
G01X374016Y418110D02*
X543307D01*
G01X370079Y422047D02*
G03X374016Y418110I3937J0D01*
G01X370079Y475984D02*
Y422047D01*
G01X396063Y368110D02*
G03X379528I-8268J0D01*
G01X396063D02*
G03X379528I-8268J0D01*
G01X396063D02*
G03X379528I-8268J0D01*
G01X396063D02*
G03X379528I-8268J0D01*
G01X396063D02*
G03X379528I-8268J0D01*
G01X396063D02*
G03X379528I-8268J0D01*
G01X374016Y410236D02*
G03X370079Y406299I0J-3937D01*
G01X543307Y410236D02*
X374016D01*
G01X407087Y487795D02*
G03Y479921I0J-3937D01*
G01X381890D02*
G03Y487795I0J3937D01*
G01X396063Y507480D02*
G03X379528I-8268J0D01*
G01D02*
G03X396063I8267J0D01*
G01D02*
G03X379528I-8268J0D01*
G01D02*
G03X396063I8267J0D01*
G01D02*
G03X379528I-8268J0D01*
G01D02*
G03X396063I8267J0D01*
G01D02*
G03X379528I-8268J0D01*
G01D02*
G03X396063I8267J0D01*
G01X379528D02*
G03X396063I8267J0D01*
G01D02*
G03X379528I-8268J0D01*
G01D02*
G03X396063I8267J0D01*
G01D02*
G03X379528I-8268J0D01*
G01X374016Y487795D02*
X543307D01*
G01X370079Y491732D02*
G03X374016Y487795I3937J0D01*
G01X370079Y545669D02*
Y491732D01*
G01X374016Y479921D02*
G03X370079Y475984I0J-3937D01*
G01X543307Y479921D02*
X374016D01*
G01X407087Y557480D02*
G03Y549606I0J-3937D01*
G01X381890D02*
G03Y557480I0J3937D01*
G01X396063Y577165D02*
G03X379528I-8268J0D01*
G01D02*
G03X396063I8267J0D01*
G01D02*
G03X379528I-8268J0D01*
G01D02*
G03X396063I8267J0D01*
G01D02*
G03X379528I-8268J0D01*
G01D02*
G03X396063I8267J0D01*
G01D02*
G03X379528I-8268J0D01*
G01D02*
G03X396063I8267J0D01*
G01X379528D02*
G03X396063I8267J0D01*
G01D02*
G03X379528I-8268J0D01*
G01D02*
G03X396063I8267J0D01*
G01D02*
G03X379528I-8268J0D01*
G01X374016Y557480D02*
X543307D01*
G01X370079Y561417D02*
G03X374016Y557480I3937J0D01*
G01X370079Y615354D02*
Y561417D01*
G01X374016Y549606D02*
G03X370079Y545669I0J-3937D01*
G01X543307Y549606D02*
X374016D01*
G01X407087Y627165D02*
G03Y619291I0J-3937D01*
G01X381890D02*
G03Y627165I0J3937D01*
G01X396063Y646850D02*
G03X379528I-8268J0D01*
G01D02*
G03X396063I8267J0D01*
G01D02*
G03X379528I-8268J0D01*
G01D02*
G03X396063I8267J0D01*
G01D02*
G03X379528I-8268J0D01*
G01D02*
G03X396063I8267J0D01*
G01D02*
G03X379528I-8268J0D01*
G01D02*
G03X396063I8267J0D01*
G01X379528D02*
G03X396063I8267J0D01*
G01D02*
G03X379528I-8268J0D01*
G01D02*
G03X396063I8267J0D01*
G01D02*
G03X379528I-8268J0D01*
G01X374016Y627165D02*
X543307D01*
G01X370079Y631102D02*
G03X374016Y627165I3937J0D01*
G01X370079Y685039D02*
Y631102D01*
G01X374016Y688976D02*
G03X370079Y685039I0J-3937D01*
G01X543307Y688976D02*
X374016D01*
G01Y619291D02*
G03X370079Y615354I0J-3937D01*
G01X543307Y619291D02*
X374016D01*
G01X510237Y-7874D02*
G03Y0I0J3937D01*
G01X537796Y19685D02*
G03X521260I-8268J0D01*
G01D02*
G03X537796I8268J0D01*
G01D02*
G03X521260I-8268J0D01*
G01D02*
G03X537796I8268J0D01*
G01D02*
G03X521260I-8268J0D01*
G01D02*
G03X537796I8268J0D01*
G01D02*
G03X521260I-8268J0D01*
G01D02*
G03X537796I8268J0D01*
G01X521260D02*
G03X537796I8268J0D01*
G01D02*
G03X521260I-8268J0D01*
G01D02*
G03X537796I8268J0D01*
G01D02*
G03X521260I-8268J0D01*
G01X510237Y61811D02*
G03Y69685I0J3937D01*
G01X537796Y89370D02*
G03X521260I-8268J0D01*
G01D02*
G03X537796I8268J0D01*
G01D02*
G03X521260I-8268J0D01*
G01D02*
G03X537796I8268J0D01*
G01D02*
G03X521260I-8268J0D01*
G01D02*
G03X537796I8268J0D01*
G01D02*
G03X521260I-8268J0D01*
G01D02*
G03X537796I8268J0D01*
G01X521260D02*
G03X537796I8268J0D01*
G01D02*
G03X521260I-8268J0D01*
G01D02*
G03X537796I8268J0D01*
G01D02*
G03X521260I-8268J0D01*
G01X510237Y131496D02*
G03Y139370I0J3937D01*
G01X537796Y159055D02*
G03X521260I-8268J0D01*
G01D02*
G03X537796I8268J0D01*
G01D02*
G03X521260I-8268J0D01*
G01D02*
G03X537796I8268J0D01*
G01D02*
G03X521260I-8268J0D01*
G01D02*
G03X537796I8268J0D01*
G01D02*
G03X521260I-8268J0D01*
G01D02*
G03X537796I8268J0D01*
G01X521260D02*
G03X537796I8268J0D01*
G01D02*
G03X521260I-8268J0D01*
G01D02*
G03X537796I8268J0D01*
G01D02*
G03X521260I-8268J0D01*
G01X510237Y270866D02*
G03Y278740I0J3937D01*
G01Y201181D02*
G03Y209055I0J3937D01*
G01X537796Y228740D02*
G03X521260I-8268J0D01*
G01D02*
G03X537796I8268J0D01*
G01D02*
G03X521260I-8268J0D01*
G01D02*
G03X537796I8268J0D01*
G01D02*
G03X521260I-8268J0D01*
G01D02*
G03X537796I8268J0D01*
G01D02*
G03X521260I-8268J0D01*
G01D02*
G03X537796I8268J0D01*
G01X521260D02*
G03X537796I8268J0D01*
G01D02*
G03X521260I-8268J0D01*
G01D02*
G03X537796I8268J0D01*
G01D02*
G03X521260I-8268J0D01*
G01X510237Y340551D02*
G03Y348425I0J3937D01*
G01X521260Y368110D02*
G03X537796I8268J0D01*
G01X521260D02*
G03X537796I8268J0D01*
G01X521260D02*
G03X537796I8268J0D01*
G01X521260D02*
G03X537796I8268J0D01*
G01X521260D02*
G03X537796I8268J0D01*
G01X521260D02*
G03X537796I8268J0D01*
G01Y298425D02*
G03X521260I-8268J0D01*
G01D02*
G03X537796I8268J0D01*
G01D02*
G03X521260I-8268J0D01*
G01D02*
G03X537796I8268J0D01*
G01D02*
G03X521260I-8268J0D01*
G01D02*
G03X537796I8268J0D01*
G01D02*
G03X521260I-8268J0D01*
G01D02*
G03X537796I8268J0D01*
G01X521260D02*
G03X537796I8268J0D01*
G01D02*
G03X521260I-8268J0D01*
G01D02*
G03X537796I8268J0D01*
G01D02*
G03X521260I-8268J0D01*
G01X510237Y410236D02*
G03Y418110I0J3937D01*
G01X537796Y437795D02*
G03X521260I-8268J0D01*
G01D02*
G03X537796I8268J0D01*
G01D02*
G03X521260I-8268J0D01*
G01D02*
G03X537796I8268J0D01*
G01D02*
G03X521260I-8268J0D01*
G01D02*
G03X537796I8268J0D01*
G01D02*
G03X521260I-8268J0D01*
G01D02*
G03X537796I8268J0D01*
G01X521260D02*
G03X537796I8268J0D01*
G01D02*
G03X521260I-8268J0D01*
G01D02*
G03X537796I8268J0D01*
G01D02*
G03X521260I-8268J0D01*
G01X537796Y368110D02*
G03X521260I-8268J0D01*
G01X537796D02*
G03X521260I-8268J0D01*
G01X537796D02*
G03X521260I-8268J0D01*
G01X537796D02*
G03X521260I-8268J0D01*
G01X537796D02*
G03X521260I-8268J0D01*
G01X537796D02*
G03X521260I-8268J0D01*
G01X510237Y479921D02*
G03Y487795I0J3937D01*
G01X537796Y507480D02*
G03X521260I-8268J0D01*
G01D02*
G03X537796I8268J0D01*
G01D02*
G03X521260I-8268J0D01*
G01D02*
G03X537796I8268J0D01*
G01D02*
G03X521260I-8268J0D01*
G01D02*
G03X537796I8268J0D01*
G01D02*
G03X521260I-8268J0D01*
G01D02*
G03X537796I8268J0D01*
G01X521260D02*
G03X537796I8268J0D01*
G01D02*
G03X521260I-8268J0D01*
G01D02*
G03X537796I8268J0D01*
G01D02*
G03X521260I-8268J0D01*
G01X510237Y549606D02*
G03Y557480I0J3937D01*
G01X537796Y577165D02*
G03X521260I-8268J0D01*
G01D02*
G03X537796I8268J0D01*
G01D02*
G03X521260I-8268J0D01*
G01D02*
G03X537796I8268J0D01*
G01D02*
G03X521260I-8268J0D01*
G01D02*
G03X537796I8268J0D01*
G01D02*
G03X521260I-8268J0D01*
G01D02*
G03X537796I8268J0D01*
G01X521260D02*
G03X537796I8268J0D01*
G01D02*
G03X521260I-8268J0D01*
G01D02*
G03X537796I8268J0D01*
G01D02*
G03X521260I-8268J0D01*
G01X510237Y619291D02*
G03Y627165I0J3937D01*
G01X537796Y646850D02*
G03X521260I-8268J0D01*
G01D02*
G03X537796I8268J0D01*
G01D02*
G03X521260I-8268J0D01*
G01D02*
G03X537796I8268J0D01*
G01D02*
G03X521260I-8268J0D01*
G01D02*
G03X537796I8268J0D01*
G01D02*
G03X521260I-8268J0D01*
G01D02*
G03X537796I8268J0D01*
G01X521260D02*
G03X537796I8268J0D01*
G01D02*
G03X521260I-8268J0D01*
G01D02*
G03X537796I8268J0D01*
G01D02*
G03X521260I-8268J0D01*
G01X539370Y-19685D02*
G03X547244Y-11811I0J7874D01*
G01X535433Y0D02*
G03Y-7874I0J-3937D01*
G01X547244D02*
Y-11811D01*
G01X535433Y-7874D02*
X547244D01*
G01Y3937D02*
Y57874D01*
G01X543307Y0D02*
G03X547244Y3937I0J3937D01*
G01X535433Y69685D02*
G03Y61811I0J-3937D01*
G01X547244Y73622D02*
Y127559D01*
G01X543307Y69685D02*
G03X547244Y73622I0J3937D01*
G01Y57874D02*
G03X543307Y61811I-3937J0D01*
G01X535433Y139370D02*
G03Y131496I0J-3937D01*
G01X547244Y143307D02*
Y197244D01*
G01X543307Y139370D02*
G03X547244Y143307I0J3937D01*
G01Y127559D02*
G03X543307Y131496I-3937J0D01*
G01X535433Y278740D02*
G03Y270866I0J-3937D01*
G01Y209055D02*
G03Y201181I0J-3937D01*
G01X543307Y278740D02*
G03X547244Y282677I0J3937D01*
G01Y212992D02*
Y266929D01*
G01X543307Y209055D02*
G03X547244Y212992I0J3937D01*
G01Y266929D02*
G03X543307Y270866I-3937J0D01*
G01X547244Y197244D02*
G03X543307Y201181I-3937J0D01*
G01X535433Y348425D02*
G03Y340551I0J-3937D01*
G01X547244Y352362D02*
Y406299D01*
G01X543307Y348425D02*
G03X547244Y352362I0J3937D01*
G01Y282677D02*
Y336614D01*
G01D02*
G03X543307Y340551I-3937J0D01*
G01X535433Y418110D02*
G03Y410236I0J-3937D01*
G01X547244Y422047D02*
Y475984D01*
G01X543307Y418110D02*
G03X547244Y422047I0J3937D01*
G01Y406299D02*
G03X543307Y410236I-3937J0D01*
G01X535433Y487795D02*
G03Y479921I0J-3937D01*
G01X547244Y491732D02*
Y545669D01*
G01X543307Y487795D02*
G03X547244Y491732I0J3937D01*
G01Y475984D02*
G03X543307Y479921I-3937J0D01*
G01X535433Y557480D02*
G03Y549606I0J-3937D01*
G01X547244Y561417D02*
Y615354D01*
G01X543307Y557480D02*
G03X547244Y561417I0J3937D01*
G01Y545669D02*
G03X543307Y549606I-3937J0D01*
G01X535433Y627165D02*
G03Y619291I0J-3937D01*
G01X547244Y631102D02*
Y685039D01*
G01X543307Y627165D02*
G03X547244Y631102I0J3937D01*
G01Y685039D02*
G03X543307Y688976I-3937J0D01*
G01X547244Y615354D02*
G03X543307Y619291I-3937J0D01*
M02*
